G04 ================== begin FILE IDENTIFICATION RECORD ==================*
G04 Layout Name:  9048_F0T_Management_Board_D_brd_V04_1213_1625.brd*
G04 Film Name:    in4*
G04 File Format:  Gerber RS274X*
G04 File Origin:  Cadence Allegro 17.2-S081*
G04 Origin Date:  Tue Dec 13 16:31:11 2022*
G04 *
G04 Layer:  DRAWING FORMAT/TITLE_BLOCK_A*
G04 Layer:  VIA CLASS/IN4*
G04 Layer:  PIN/IN4*
G04 Layer:  MANUFACTURING/PHOTOPLOT_OUTLINE*
G04 Layer:  ETCH/IN4*
G04 Layer:  DRAWING FORMAT/TITLE_BLOCK*
G04 Layer:  DRAWING FORMAT/TITLE_DATA_IN4*
G04 *
G04 Offset:    (0.00 0.00)*
G04 Mirror:    No*
G04 Mode:      Positive*
G04 Rotation:  0*
G04 FullContactRelief:  No*
G04 UndefLineWidth:     6.00*
G04 ================== end FILE IDENTIFICATION RECORD ====================*
%FSLAX25Y25*MOIN*%
%IR0*IPPOS*OFA0.00000B0.00000*MIA0B0*SFA1.00000B1.00000*%
%ADD11C,.02*%
%ADD13C,.0315*%
%ADD12C,.018*%
%ADD10C,.085*%
%ADD14C,.01*%
%ADD15C,.015*%
%ADD16C,.006*%
%ADD17C,.0033*%
%ADD18C,.0034*%
%ADD19C,.0045*%
%ADD20C,.00339*%
%ADD21C,.03004*%
%ADD22C,.02604*%
G75*
%LPD*%
G75*
G36*
G01X331081Y468024D02*
X332262D01*
X332646Y467640D01*
Y451968D01*
G03X336614Y448000I3969J1D01*
G01X346457D01*
G02X352331Y442126I0J-5874D01*
G01Y336646D01*
X345472D01*
G03X341504Y332678I0J-3968D01*
G01Y322834D01*
G03X345472Y318866I3968J0D01*
G01X352331D01*
Y7874D01*
G02X346457Y2000I-5874J0D01*
G01X7874D01*
G02X2000Y7874I0J5874D01*
G01Y318866D01*
X8858D01*
G03X12827Y322835I0J3969D01*
G01Y332677D01*
G03X8858Y336646I-3969J0D01*
G01X2000D01*
Y442126D01*
G02X7874Y448000I5874J0D01*
G01X17717D01*
G03X21685Y451968I-1J3969D01*
G01Y467365D01*
X22132Y467812D01*
X23372D01*
X23682Y467502D01*
Y451968D01*
G02X17717Y446002I-5966J0D01*
G01X7874D01*
G03X3998Y442126I0J-3876D01*
G01Y338644D01*
X8858D01*
G02X14824Y332677I-1J-5967D01*
G01Y322833D01*
G02X8858Y316868I-5966J1D01*
G01X3998D01*
Y7874D01*
G03X7874Y3998I3876J0D01*
G01X250882D01*
X301602D01*
X346457D01*
G03X350334Y7874I0J3877D01*
G01Y316868D01*
X345472D01*
G02X339506Y322834I0J5967D01*
G01Y332678D01*
G02X345472Y338644I5966J-1D01*
G01X350334D01*
Y442126D01*
G03X346459Y446002I-3876J0D01*
G01X336614D01*
G02X330648Y451968I0J5966D01*
G01Y467591D01*
X331081Y468024D01*
G37*
G36*
G01X32560Y316299D02*
X37577D01*
G03X37637Y316298I53J1365D01*
G01X38069D01*
X42834Y311534D01*
X42862Y311505D01*
G03X42886Y311481I978J954D01*
G01X43004Y311363D01*
Y299533D01*
G03X43404Y298567I1366J0D01*
G01X44794Y297177D01*
Y277641D01*
X44785Y277612D01*
G03X44718Y277170I1435J-444D01*
G03X45100Y276169I1503J0D01*
G01Y269558D01*
X41976Y266434D01*
Y250741D01*
G02X41476Y250354I-400J0D01*
G03X41100Y250402I-377J-1454D01*
G03Y247398I0J-1502D01*
G03X41476Y247446I-1J1502D01*
G02X41976Y247059I100J-387D01*
G01Y230775D01*
X34200Y223001D01*
Y218073D01*
G03X34198Y218000I1500J-78D01*
G03X34200Y217927I1502J5D01*
G01Y209732D01*
X43652Y200279D01*
Y199632D01*
G03X43965Y198878I1067J1D01*
G01X49141Y193701D01*
Y180219D01*
X50339Y179021D01*
Y132525D01*
G02X49791Y132154I-400J0D01*
G03X49236Y132260I-554J-1396D01*
G03X47734Y130758I0J-1502D01*
G03X48313Y129573I1502J0D01*
G02Y128943I-246J-315D01*
G03X47734Y127758I923J-1185D01*
G03X49236Y126256I1502J0D01*
G03X49791Y126362I1J1502D01*
G02X50339Y125991I148J-371D01*
G01Y116973D01*
X47965Y114599D01*
X26970D01*
X26296Y115273D01*
G03X26702Y116300I-1096J1027D01*
G03X25200Y117802I-1502J0D01*
G03X24245Y117459I0J-1501D01*
G01X15304Y126400D01*
Y221604D01*
X15800Y222100D01*
X21300D01*
X23300Y224100D01*
Y227700D01*
X21900Y229100D01*
X16604D01*
X15304Y230400D01*
Y254383D01*
G02X15990Y254663I400J0D01*
G03X17065Y254210I1075J1049D01*
G03Y257214I0J1502D01*
G03X15990Y256761I0J-1502D01*
G02X15304Y257041I-286J280D01*
G01Y307443D01*
X24160Y316299D01*
X28840D01*
G02X29231Y315815I0J-400D01*
G03X29198Y315500I1469J-313D01*
G03X32202I1502J0D01*
G03X32169Y315815I-1502J2D01*
G02X32560Y316299I391J84D01*
G37*
G36*
G01X38828Y468024D02*
X40009D01*
X40382Y467651D01*
Y451968D01*
G03X44350Y448000I3969J1D01*
G01X45976D01*
X46336Y447640D01*
Y446364D01*
X45974Y446002D01*
X44350D01*
G02X38384Y451968I0J5966D01*
G01Y467580D01*
X38828Y468024D01*
G37*
G36*
G01X68550Y153750D02*
X80750D01*
X87500Y147000D01*
Y130500D01*
X89500Y128500D01*
Y118000D01*
X90500Y117000D01*
Y115800D01*
X92100Y114200D01*
X93300D01*
X94200Y113300D01*
Y90500D01*
X97804Y86896D01*
Y82204D01*
X96400Y80800D01*
X66360D01*
X64860Y82300D01*
Y109539D01*
X68626Y120527D01*
Y128047D01*
G03X68628Y128100I-1499J83D01*
G03X68626Y128153I-1501J-30D01*
G01Y136969D01*
X67318Y138278D01*
Y152518D01*
X68550Y153750D01*
G37*
G36*
G01X88455Y313045D02*
X77445D01*
X74516Y310116D01*
Y297561D01*
X75182Y296895D01*
X88395D01*
X89200Y297700D01*
Y312300D01*
X88455Y313045D01*
G37*
G36*
G01X213544Y176513D02*
X216368D01*
X216665Y176216D01*
G02X216691Y175679I-283J-283D01*
G03X216395Y174852I1007J-827D01*
G03X217138Y173676I1302J0D01*
G01Y172225D01*
X216198Y171285D01*
G03X215564Y169753I1532J-1531D01*
G01Y155510D01*
G03X215701Y154750I2166J-2D01*
G01X215746Y154629D01*
X191867Y130750D01*
X191763Y130770D01*
G03X191482Y130796I-278J-1476D01*
G03X189980Y129294I0J-1502D01*
G03X190006Y129013I1502J-3D01*
G01X190026Y128909D01*
X187803Y126686D01*
G02X187243Y126681I-283J283D01*
G03X186200Y127102I-1043J-1081D01*
G03X184698Y125600I0J-1502D01*
G03X184951Y124766I1501J0D01*
G02X184696Y124152I-333J-222D01*
G01X173848Y121993D01*
G03X173592Y121916I264J-1341D01*
G01X171780Y121166D01*
G03X171337Y120869I525J-1262D01*
G01X168357Y117890D01*
X164042D01*
X163986Y117997D01*
G03X161328I-1329J-700D01*
G01X161272Y117890D01*
X159206D01*
G03X157634I-786J-1280D01*
G01X156363D01*
G03X154697I-833J-1251D01*
G01X152370D01*
X152336Y117903D01*
G03X151800Y118002I-536J-1403D01*
G03X151331Y117927I0J-1502D01*
G01X151301Y117917D01*
X148991D01*
X144863Y122045D01*
X144849Y122096D01*
G03X143796Y123149I-1449J-396D01*
G01X143745Y123163D01*
X141563Y125345D01*
Y137170D01*
X142102Y137709D01*
X143953D01*
X143987Y137675D01*
X148353D01*
X148403Y137548D01*
G03X148877Y136915I1397J552D01*
G02Y136285I-246J-315D01*
G03X148298Y135100I923J-1185D01*
G03X151302I1502J0D01*
G03X150723Y136285I-1502J0D01*
G02Y136915I246J315D01*
G03X150922Y137101I-922J1186D01*
G02X151504Y137118I299J-266D01*
G01X153676Y134946D01*
Y128604D01*
X155385Y126895D01*
X167289D01*
X167301Y126707D01*
G03X168800Y125298I1499J93D01*
G03X170254Y126423I0J1502D01*
G02X170689Y126720I387J-100D01*
G03X170867Y126709I181J1491D01*
G03X172369Y128211I0J1502D01*
G03X171949Y129253I-1503J0D01*
G01X171812Y129395D01*
X173573Y131155D01*
X173705Y131082D01*
G03X174436Y130892I731J1311D01*
G03X175938Y132394I0J1502D01*
G03X175748Y133125I-1501J0D01*
G01X175675Y133257D01*
X182139Y139721D01*
G02X182754Y139662I283J-282D01*
G03X184000Y138998I1246J837D01*
G03X185502Y140500I0J1502D01*
G03X184838Y141746I-1501J0D01*
G02X184779Y142361I223J332D01*
G01X197881Y155464D01*
X197903Y155477D01*
G03X198365Y155939I-660J1122D01*
G01X198378Y155961D01*
X201028Y158611D01*
X201051Y158624D01*
G03X201517Y159091I-659J1123D01*
G01X201530Y159113D01*
X201720Y159303D01*
G02X202365Y159192I283J-282D01*
G03X203542Y158446I1177J556D01*
G03X204844Y159748I0J1302D01*
G03X203857Y161011I-1302J0D01*
G01X203803Y161025D01*
X203622Y161205D01*
X203820Y161403D01*
X203746Y161477D01*
X203920Y161651D01*
X203964Y161666D01*
G03X204844Y162898I-422J1232D01*
G03X203942Y164137I-1302J0D01*
G01X203804Y164182D01*
Y164763D01*
X203942Y164808D01*
G03Y167286I-400J1239D01*
G01X203804Y167331D01*
Y167913D01*
X203942Y167958D01*
G03Y170436I-400J1239D01*
G01X203804Y170481D01*
Y172268D01*
X204505Y172969D01*
X211255D01*
X211949Y173663D01*
Y174918D01*
X213544Y176513D01*
G37*
G36*
G01X144160Y190600D02*
X145928D01*
X147390Y189138D01*
G03X148152Y188798I825J825D01*
G03X149100Y188461I948J1165D01*
G03X150600Y189890I0J1502D01*
G01X150609Y190080D01*
X158128D01*
X160503Y187705D01*
G02X160434Y187084I-283J-283D01*
G03X159735Y185815I802J-1269D01*
G03X162739I1502J0D01*
G03X162605Y186435I-1501J0D01*
G02X162969Y187000I364J165D01*
G01X177642D01*
G03X179050I704J1094D01*
G01X180791D01*
G03X182199I704J1094D01*
G01X183941D01*
G03X185349I704J1094D01*
G01X190240D01*
G03X191648I704J1094D01*
G01X211400D01*
X212021Y186379D01*
G02X212032Y185826I-283J-282D01*
G03X211689Y184945I960J-881D01*
G03X212411Y183779I1303J0D01*
G01X212440Y183765D01*
X212660Y183543D01*
Y183062D01*
X212531Y183013D01*
G03Y180577I460J-1218D01*
G01X212660Y180528D01*
Y177045D01*
X210948Y175333D01*
Y175318D01*
X209647Y174018D01*
X205859D01*
X205330Y174547D01*
Y176813D01*
X204308Y177835D01*
X198895D01*
G02X198506Y178332I-1J400D01*
G03X198545Y178646I-1263J316D01*
G03X195941I-1302J0D01*
G03X195980Y178332I1302J2D01*
G02X195591Y177835I-388J-97D01*
G01X194215D01*
X194125Y177925D01*
G03X193300Y178266I-824J-825D01*
G01X192646D01*
G02X192246Y178662I0J400D01*
G03X190944Y179948I-1302J-16D01*
G03X189666Y178895I0J-1302D01*
G01X189662Y178875D01*
X189578Y178672D01*
X189305Y178785D01*
X189029Y179061D01*
X189014Y179101D01*
G03X187794Y179948I-1220J-455D01*
G03X186492Y178646I0J-1302D01*
G03X186502Y178486I1302J1D01*
G02X186287Y178262I-199J-24D01*
G03X186190Y178266I-97J-1162D01*
G01X185936D01*
Y178478D01*
X185938Y178490D01*
G03X185947Y178646I-1293J153D01*
G03X183343I-1302J0D01*
G03X183352Y178490I1302J-3D01*
G01X183354Y178478D01*
Y178266D01*
X182786D01*
Y178478D01*
X182788Y178490D01*
G03X182797Y178646I-1293J153D01*
G03X181495Y179948I-1302J0D01*
G03X180193Y178662I0J-1302D01*
G02X179793Y178266I-400J4D01*
G01X176600D01*
G03X175775Y177925I-1J-1166D01*
G01X160275Y162425D01*
G03X160161Y162292I826J-824D01*
G02X159921Y162227I-161J119D01*
G03X159328Y162349I-593J-1380D01*
G03X157826Y160847I0J-1502D01*
G03X158249Y159802I1502J0D01*
G02X158247Y159521I-143J-139D01*
G01X156117Y157391D01*
X156067Y157377D01*
G03X155037Y156347I414J-1444D01*
G01X155023Y156297D01*
X147745Y149019D01*
G03X147092Y148366I684J-1337D01*
G01X146193Y147467D01*
X142471D01*
X141419Y148519D01*
Y156086D01*
X143066Y157734D01*
X147600D01*
G03X148566Y158134I0J1366D01*
G01X149366Y158934D01*
X151400D01*
G03X152366Y159334I0J1366D01*
G01X155666Y162634D01*
G03X156066Y163600I-966J966D01*
G01Y164834D01*
X170024Y178792D01*
X170062Y178807D01*
G03X171002Y180200I-562J1393D01*
G03X169500Y181702I-1502J0D01*
G03X168107Y180762I0J-1502D01*
G01X168092Y180724D01*
X153734Y166366D01*
G03X153334Y165400I966J-966D01*
G01Y164166D01*
X150834Y161666D01*
X148800D01*
G03X148177Y161516I-1J-1366D01*
G02X147639Y161691I-182J356D01*
G03X146862Y162403I-1339J-681D01*
G01X146824Y162418D01*
X146576Y162666D01*
G03X145610Y163066I-966J-966D01*
G01X137850D01*
Y173200D01*
X139170Y174520D01*
X148970D01*
X150860Y176410D01*
Y177156D01*
X151008Y177195D01*
G03X151579Y177491I-390J1451D01*
G02X152108Y177475I255J-308D01*
G03X153134Y177070I1026J1097D01*
G03Y180074I0J1502D01*
G03X152174Y179727I0J-1501D01*
G02X151645Y179743I-255J308D01*
G03X151008Y180097I-1026J-1097D01*
G01X150860Y180136D01*
Y183738D01*
G03X151507Y184973I-855J1235D01*
G03X150005Y186475I-1502J0D01*
G03X148653Y185626I0J-1501D01*
G01X144044D01*
X143220Y186450D01*
Y189660D01*
X144160Y190600D01*
G37*
G36*
G01X189081Y175695D02*
G02X189629Y176125I395J61D01*
G01X189878Y176022D01*
G03X190324Y175934I444J1078D01*
G01X192165D01*
Y171015D01*
X191775Y170625D01*
G03X191566Y170341I824J-826D01*
G03X190944Y170499I-622J-1145D01*
G03X189642Y169197I0J-1302D01*
G03X189940Y168368I1302J0D01*
G01X190055Y168228D01*
X188763Y166936D01*
X188623Y167051D01*
G03X187794Y167349I-829J-1004D01*
G03X186492Y166047I0J-1302D01*
G03X186633Y165457I1302J-1D01*
G03X186475Y165325I666J-958D01*
G01X185375Y164225D01*
G03X185237Y164058I826J-823D01*
G03X184645Y164200I-591J-1160D01*
G03X183343Y162898I0J-1302D01*
G03X183369Y162638I1302J-1D01*
G02X183236Y162408I-196J-40D01*
G03X183039Y162323I362J-1109D01*
G02X182750Y162551I-96J175D01*
G03X182797Y162898I-1255J347D01*
G03X181495Y161596I-1302J0D01*
G03X181803Y161633I0J1302D01*
G02X182019Y161331I47J-194D01*
G03X181925Y161152I982J-630D01*
G02X181708Y161033I-184J78D01*
G03X181495Y161050I-210J-1285D01*
G03X180193Y159748I0J-1302D01*
G03X180311Y159207I1302J1D01*
G03X180075Y159025I589J-1007D01*
G01X179075Y158025D01*
G03X178889Y157782I825J-824D01*
G03X178346Y157901I-544J-1183D01*
G03X177044Y156599I0J-1302D01*
G03X177342Y155770I1302J0D01*
G01X177458Y155630D01*
X176155Y154328D01*
X176022Y154407D01*
G03X175359Y154588I-662J-1121D01*
G03X174516Y154278I0J-1301D01*
G02X173969Y154305I-259J305D01*
G03X172890Y154762I-1079J-1045D01*
G03X171388Y153260I0J-1502D01*
G03X171624Y152451I1502J-1D01*
G02X171287Y151836I-337J-215D01*
G01X163270D01*
X162979Y151545D01*
G03X161900Y152002I-1079J-1045D01*
G03X160398Y150500I0J-1502D01*
G03X160855Y149421I1502J0D01*
G01X153300Y141866D01*
X150130D01*
X149134Y142862D01*
Y146356D01*
G03X149931Y147682I-705J1326D01*
G03X149590Y148635I-1502J0D01*
G01X149475Y148775D01*
X155491Y154791D01*
X155628Y154697D01*
G03X156481Y154431I853J1235D01*
G03X157983Y155933I0J1502D01*
G03X157616Y156916I-1502J-1D01*
G01X158051Y157351D01*
G02X158734Y157068I283J-283D01*
G01Y156549D01*
X158694Y156495D01*
G03X158398Y155600I1205J-895D01*
G03X161402I1502J0D01*
G03X161106Y156495I-1501J0D01*
G01X161066Y156549D01*
Y156777D01*
G02X161376Y156944I200J0D01*
G03X162200Y156698I824J1257D01*
G03X163702Y158200I0J1502D01*
G03X162420Y159686I-1502J0D01*
G02X162252Y159915I29J198D01*
G03X162266Y160100I-1152J180D01*
G01Y161117D01*
X171022Y169872D01*
G02X171681Y169725I283J-283D01*
G03X173000Y168798I1319J475D01*
G03X174402Y170200I0J1402D01*
G03X174345Y170597I-1402J1D01*
G02X174838Y171095I383J114D01*
G03X175196Y171045I357J1252D01*
G03X176498Y172347I0J1302D01*
G03X175575Y173593I-1303J0D01*
G02X175408Y174258I116J383D01*
G01X176434Y175285D01*
G02X177100Y175118I283J-283D01*
G03X178346Y174194I1246J378D01*
G03X179648Y175496I0J1302D01*
G03X179632Y175702I-1302J2D01*
G01X179629Y175718D01*
Y175934D01*
X180212D01*
Y175718D01*
X180209Y175702D01*
G03X180193Y175496I1286J-204D01*
G03X182797I1302J0D01*
G03X182781Y175702I-1302J2D01*
G01X182778Y175718D01*
Y175934D01*
X183362D01*
Y175718D01*
X183359Y175702D01*
G03X183343Y175496I1286J-204D01*
G03X184645Y174194I1302J0D01*
G03X185851Y175005I0J1302D01*
G02X186504Y175136I370J-152D01*
G01X186559Y175081D01*
X186574Y175041D01*
G03X187794Y174194I1220J455D01*
G03X189096Y175496I0J1302D01*
G03X189081Y175695I-1302J2D01*
G37*
G36*
G01X148208Y206608D02*
X153208D01*
X155332Y204484D01*
G03X154965Y203500I1136J-984D01*
G03X155117Y202842I1502J0D01*
G02X154757Y202266I-360J-176D01*
G01X154100D01*
G03X153275Y201925I-1J-1166D01*
G01X152346Y200996D01*
X152280Y200986D01*
G03X150998Y199500I220J-1486D01*
G03X152500Y197998I1502J0D01*
G03X153986Y199280I0J1502D01*
G01X153996Y199346D01*
X154583Y199934D01*
X157417D01*
X158275Y199075D01*
G03X158726Y198795I825J825D01*
G01X158770Y198780D01*
X162809Y194741D01*
G03X163634Y194400I824J825D01*
G01X169124D01*
G02X169477Y193810I0J-400D01*
G03X169298Y193100I1323J-711D01*
G03X172302I1502J0D01*
G03X172123Y193810I-1502J-1D01*
G02X172476Y194400I353J190D01*
G01X172966D01*
G03X173667Y194634I0J1167D01*
G01X182100D01*
G03X182925Y194975I1J1166D01*
G01X183847Y195897D01*
X186488D01*
X186720Y195664D01*
X206965D01*
X207197Y195897D01*
X225079D01*
X226432Y194543D01*
Y192877D01*
G02X225919Y192493I-400J0D01*
G03X225552Y192546I-368J-1249D01*
G03Y189942I0J-1302D01*
G03X225919Y189995I-1J1302D01*
G02X226432Y189611I113J-384D01*
G01Y189234D01*
X226184D01*
X226141Y189256D01*
G03X225552Y189397I-589J-1160D01*
G03Y186793I0J-1302D01*
G03X225919Y186846I-1J1302D01*
G02X226432Y186462I113J-384D01*
G01Y186084D01*
X226184D01*
X226141Y186106D01*
G03X225552Y186247I-589J-1160D01*
G03Y183643I0J-1302D01*
G03X225919Y183696I-1J1302D01*
G02X226432Y183312I113J-384D01*
G01Y181666D01*
X225560Y180794D01*
X219469D01*
X212311Y187952D01*
X211864D01*
X211815Y188002D01*
X192256D01*
X192243Y188187D01*
G03X189645I-1299J-92D01*
G01X189632Y188002D01*
X185957D01*
X185944Y188187D01*
G03X183346I-1299J-92D01*
G01X183333Y188002D01*
X182807D01*
X182794Y188187D01*
G03X180196I-1299J-92D01*
G01X180183Y188002D01*
X179658D01*
X179645Y188187D01*
G03X177047I-1299J-92D01*
G01X177034Y188002D01*
X161623D01*
X161301Y188324D01*
G02X161511Y189000I283J283D01*
G03X162742Y190477I-271J1477D01*
G03X161240Y191979I-1502J0D01*
G03X159763Y190748I0J-1502D01*
G02X159087Y190538I-393J73D01*
G01X158543Y191082D01*
X150102D01*
G03X149307Y191451I-1002J-1119D01*
G01X149240Y191460D01*
X146000Y194700D01*
Y204400D01*
X148208Y206608D01*
G37*
G36*
G01X196637Y176494D02*
X201880D01*
X202347Y176027D01*
X202307Y175910D01*
G03X202240Y175496I1235J-412D01*
G03X202468Y174760I1302J0D01*
G01Y169933D01*
G03Y168461I1074J-736D01*
G01Y166783D01*
G03Y165311I1074J-736D01*
G01Y163634D01*
G03X202240Y162898I1074J-736D01*
G03X202438Y162208I1301J0D01*
G01X202468Y162160D01*
Y161577D01*
X201578Y160687D01*
G02X201298Y160684I-142J141D01*
G03X200393Y161050I-905J-936D01*
G03X199091Y159748I0J-1302D01*
G03X199457Y158843I1302J0D01*
G02X199454Y158563I-144J-138D01*
G01X198428Y157537D01*
G02X198148Y157535I-141J142D01*
G03X197243Y157901I-905J-936D01*
G03X195941Y156599I0J-1302D01*
G03X196307Y155694I1302J0D01*
G02X196305Y155414I-144J-139D01*
G01X194268Y153377D01*
G02X193634Y153470I-282J283D01*
G03X192400Y154206I-1234J-666D01*
G03X190998Y152804I0J-1402D01*
G03X191734Y151570I1402J0D01*
G02X191827Y150936I-190J-352D01*
G01X174756Y133865D01*
X174656Y133880D01*
G03X174436Y133896I-219J-1486D01*
G03X172934Y132394I0J-1502D01*
G03X172950Y132174I1502J-1D01*
G01X172965Y132074D01*
X172776Y131885D01*
G02X172097Y132111I-283J283D01*
G03X170610Y133402I-1487J-211D01*
G03X169108Y131900I0J-1502D01*
G03X170399Y130413I1502J0D01*
G02X170625Y129734I-57J-396D01*
G01X170577Y129686D01*
X170522Y129673D01*
G03X169405Y128556I345J-1462D01*
G01X169392Y128501D01*
X169154Y128263D01*
X169052Y128281D01*
G03X168800Y128302I-250J-1481D01*
G03X168670Y128296I4J-1502D01*
G02X168235Y128695I-35J399D01*
G01Y128696D01*
G03X166733Y130202I-1502J4D01*
G03X165231Y128700I0J-1502D01*
G03X165253Y128445I1502J1D01*
G02X164859Y127977I-394J-68D01*
G01X155795D01*
X154781Y128991D01*
Y135788D01*
G03X155552Y137100I-731J1312D01*
G03X155495Y137511I-1502J1D01*
G02X155763Y138003I384J110D01*
G03X156827Y139440I-438J1437D01*
G03X156824Y139529I-1502J-6D01*
G01X156819Y139619D01*
X163576Y146376D01*
X166983D01*
G03X167808Y146718I0J1166D01*
G01X170190Y149100D01*
X172419D01*
X172822Y149502D01*
X175429D01*
G03X176254Y149844I0J1166D01*
G01X179599Y153189D01*
G02X180261Y153034I283J-283D01*
G03X181495Y152147I1234J415D01*
G03Y154751I0J1302D01*
G03X181283Y154734I-2J-1302D01*
G02X181053Y154962I-33J197D01*
G03X181066Y155118I-1153J175D01*
G02X181297Y155312I200J-4D01*
G03X181495Y155297I197J1287D01*
G03X182797Y156599I0J1302D01*
G03X182751Y156942I-1302J0D01*
G02X182850Y157171I193J53D01*
G03X183125Y157375I-550J1029D01*
G01X183300Y157550D01*
X183543Y157307D01*
X183479Y157178D01*
G03X183343Y156599I1166J-579D01*
G03X184645Y157901I1302J0D01*
G03X184065Y157765I-1J-1302D01*
G02X183833Y158084I-89J179D01*
G03X184050Y158392I-832J817D01*
G02X184285Y158497I180J-87D01*
G03X184645Y158446I361J1251D01*
G03X185947Y159748I0J1302D01*
G03X185840Y160266I-1302J1D01*
G03X186125Y160475I-539J1034D01*
G01X187025Y161375D01*
G03X187259Y161711I-825J824D01*
G03X187794Y161596I535J1187D01*
G03X189096Y162898I0J1302D01*
G03X189080Y163102I-1302J1D01*
G01X189077Y163118D01*
Y163334D01*
X189661D01*
Y163118D01*
X189658Y163102D01*
G03X189642Y162898I1286J-203D01*
G03X192246I1302J0D01*
G03X192194Y163262I-1302J0D01*
G02X192286Y163491I192J56D01*
G03X192525Y163675I-586J1009D01*
G01X192810Y163961D01*
X193063Y163708D01*
X192981Y163574D01*
G03X192792Y162898I1113J-676D01*
G03X194094Y164200I1302J0D01*
G03X193418Y164011I0J-1302D01*
G01X193284Y163929D01*
X193031Y164182D01*
X193425Y164575D01*
G03X193620Y164834I-825J824D01*
G03X194094Y164745I473J1213D01*
G03Y167349I0J1302D01*
G03X193983Y167344I3J-1302D01*
G02X193766Y167544I-17J200D01*
G01Y167700D01*
G02X193983Y167900I200J0D01*
G03X194094Y167895I114J1297D01*
G03X195396Y169197I0J1302D01*
G03X195059Y170071I-1302J0D01*
G02X195072Y170623I296J269D01*
G01X195825Y171375D01*
G03X196166Y172200I-825J824D01*
G01Y172848D01*
X196242Y172923D01*
Y176099D01*
X196637Y176494D01*
G37*
G36*
G01X192504Y214334D02*
X205548D01*
X207200Y212682D01*
Y208654D01*
G02X206775Y208254I-400J-1D01*
G03X206692Y208257I-88J-1299D01*
G03Y205653I0J-1302D01*
G03X206775Y205656I-5J1302D01*
G02X207200Y205256I25J-399D01*
G01Y202727D01*
X207212Y202715D01*
Y197328D01*
X206550Y196666D01*
X205186D01*
G02X204800Y197169I0J400D01*
G03X204844Y197506I-1258J336D01*
G03X202240I-1302J0D01*
G03X202284Y197169I1302J-1D01*
G02X201898Y196666I-386J-103D01*
G01X198887D01*
G02X198501Y197169I0J400D01*
G03X198545Y197506I-1258J336D01*
G03X195941I-1302J0D01*
G03X195985Y197169I1302J-1D01*
G02X195599Y196666I-386J-103D01*
G01X192588D01*
G02X192202Y197169I0J400D01*
G03X192246Y197506I-1258J336D01*
G03X189642I-1302J0D01*
G03X189686Y197169I1302J-1D01*
G02X189300Y196666I-386J-103D01*
G01X187135D01*
X186654Y197147D01*
Y201604D01*
X187225Y202175D01*
G03X187566Y203000I-825J824D01*
G01Y207600D01*
G03X187225Y208425I-1166J1D01*
G01X186931Y208719D01*
X187167Y208955D01*
X187291Y208903D01*
G03X187794Y208802I503J1202D01*
G03Y211406I0J1302D01*
G03X187228Y211276I1J-1302D01*
G02X186654Y211637I-174J360D01*
G01Y211721D01*
G02X187228Y212082I400J1D01*
G03X187794Y211952I567J1172D01*
G03X189096Y213254I0J1302D01*
G03X188988Y213774I-1302J1D01*
G02X189354Y214334I366J160D01*
G01X189384D01*
G02X189750Y213774I0J-400D01*
G03X189642Y213254I1194J-519D01*
G03X192246I1302J0D01*
G03X192138Y213774I-1302J1D01*
G02X192504Y214334I366J160D01*
G37*
G36*
G01X217952Y115769D02*
X231272D01*
Y111975D01*
X231133Y111930D01*
G03Y109070I459J-1430D01*
G01X231272Y109025D01*
Y105662D01*
X217952D01*
Y115769D01*
G37*
G36*
G01X232954Y181253D02*
X238000D01*
X238332Y180921D01*
X238335Y180843D01*
G03X239856Y179109I1842J81D01*
G02X240019Y178876I-34J-197D01*
G03X239998Y178646I1281J-233D01*
G03X240074Y178209I1302J1D01*
G02X239981Y177966I-189J-67D01*
G03X238588Y175620I1279J-2346D01*
G01Y171985D01*
G03X238736Y171004I3335J1D01*
G02X238306Y170490I-382J-117D01*
G03X238150Y170499I-153J-1293D01*
G03X239452Y169197I0J-1302D01*
G03X239451Y169250I-1302J2D01*
G01X239448Y169338D01*
X239652Y169541D01*
X239824Y169368D01*
G02X240370Y168049I-1320J-1319D01*
G01Y165376D01*
G03X240383Y165152I2115J10D01*
G01X240384Y165141D01*
Y164300D01*
X241704Y162980D01*
Y162588D01*
G03X241919Y161597I2396J1D01*
G02X241495Y161035I-364J-166D01*
G03X241300Y161050I-197J-1287D01*
G03X242602Y159748I0J-1302D01*
G03X242450Y160358I-1302J0D01*
G02X242740Y160617I177J94D01*
G03X243109Y160408I1361J1973D01*
G02X243216Y160162I-83J-182D01*
G03X243148Y159748I1234J-415D01*
G03X244450Y158446I1302J0D01*
G03X244783Y158490I-3J1302D01*
G01X244869Y158513D01*
X245059Y158388D01*
X245083Y158336D01*
G03X245217Y158080I2497J1144D01*
G01X244966Y157794D01*
G03X244450Y157901I-517J-1195D01*
G03X245752Y156599I0J-1302D01*
G03X245751Y156659I-1302J8D01*
G02X246332Y157033I399J18D01*
G03X247576Y156734I1246J2447D01*
G01X247950D01*
X250237Y154447D01*
G02X250248Y153894I-283J-282D01*
G03X249852Y152878I1106J-1016D01*
G01Y152877D01*
G03X251354Y151375I1502J0D01*
G03X252689Y152188I0J1503D01*
G01X252745Y152296D01*
X254229D01*
G03X256755I1263J609D01*
G01X261445D01*
G02X261788Y151691I-1J-400D01*
G03X261528Y150846I1243J-845D01*
G03X263030Y149344I1502J0D01*
G01Y149343D01*
G03X264152Y149847I-1J1503D01*
G02X264777Y149851I314J-248D01*
G03X265942Y149297I1165J948D01*
G03X266929Y149667I0J1501D01*
G02X267455I263J-302D01*
G03X268442Y149297I987J1131D01*
G03X269944Y150799I0J1502D01*
G03X269461Y151902I-1501J0D01*
G02Y152196I136J147D01*
G03X269560Y152296I-1017J1105D01*
G01X282560D01*
G03X284238I839J1247D01*
G01X285060D01*
G03X286738I839J1247D01*
G01X289377D01*
X289400Y152122D01*
G03X290889Y150816I1489J196D01*
G03X291965Y151270I0J1502D01*
G02X292555Y151252I287J-279D01*
G03X293693Y150730I1138J979D01*
G03X295190Y152112I0J1502D01*
G01X295205Y152296D01*
X296270D01*
G02X296634Y151732I-1J-400D01*
G03X296503Y151119I1371J-614D01*
G01Y151118D01*
G03X296873Y150131I1501J0D01*
G02Y149605I-302J-263D01*
G03Y147631I1131J-987D01*
G02Y147105I-302J-263D01*
G03X296503Y146118I1131J-987D01*
G03X299507I1502J0D01*
G03X299137Y147105I-1501J0D01*
G02Y147631I302J263D01*
G03Y149605I-1131J987D01*
G02Y150131I302J263D01*
G03X299507Y151118I-1131J987D01*
G01Y151119D01*
G03X299376Y151732I-1502J-1D01*
G02X299740Y152296I365J164D01*
G01X301742D01*
X303961Y150077D01*
Y137328D01*
X303840Y137276D01*
G03X303404Y136988I597J-1378D01*
G02X302878Y136967I-275J290D01*
G03X301936Y137299I-942J-1170D01*
G03Y134295I0J-1502D01*
G03X302968Y134706I0J1501D01*
G02X303494Y134727I275J-290D01*
G03X303840Y134518I943J1170D01*
G01X303961Y134466D01*
Y133931D01*
X301385Y131355D01*
X301281Y131375D01*
G03X301000Y131402I-284J-1475D01*
G03X299994Y131015I0J-1501D01*
G01X289694D01*
G02X289295Y131442I0J400D01*
G03X289298Y131542I-1499J95D01*
G03X287796Y133044I-1502J0D01*
G03X286462Y132232I0J-1502D01*
G02X285824Y132133I-355J184D01*
G01X281945Y136012D01*
X267315D01*
X265138Y133835D01*
Y131015D01*
X261830D01*
G02X261487Y131621I0J400D01*
G03X261702Y132395I-1286J774D01*
G03X258698I-1502J0D01*
G03X258913Y131621I1501J0D01*
G02X258570Y131015I-343J-206D01*
G01X254124D01*
G02X253756Y131571I0J400D01*
G03X253876Y132159I-1381J588D01*
G03X252374Y133661I-1502J0D01*
G03X251351Y133259I0J-1503D01*
G02X250795Y133268I-273J292D01*
G01X244362Y139702D01*
Y141003D01*
G03X242195Y143170I-2167J0D01*
G03X240193Y141830I1J-2167D01*
G01X239891D01*
X233653Y148068D01*
X233720Y148197D01*
G03X233886Y148883I-1336J686D01*
G01Y148884D01*
G03X232384Y150386I-1502J0D01*
G01X232382D01*
G03X232110Y150361I1J-1502D01*
G02X231636Y150754I-74J393D01*
G01Y153331D01*
G03X231002Y154862I-2166J0D01*
G01X229398Y156465D01*
Y158648D01*
G03Y160848I-695J1100D01*
G01Y161798D01*
G03X230004Y162898I-695J1100D01*
G03X229724Y163705I-1301J1D01*
G01X229704Y163730D01*
X229636Y163917D01*
X230234Y164515D01*
G03X230868Y166046I-1532J1531D01*
G01Y166047D01*
G03X229871Y167871I-2167J0D01*
G02X229761Y168440I216J337D01*
G03X230004Y169197I-1058J757D01*
G03X228799Y170496I-1303J0D01*
G01X228724Y170502D01*
X228531Y170699D01*
Y174937D01*
X228592Y174998D01*
G03X229101Y175802I-1531J1533D01*
G01X229116Y175845D01*
X230601Y177329D01*
G03X230766Y177730I-405J401D01*
G01Y178374D01*
G03X231132Y178668I-1166J1826D01*
G01X231704Y179240D01*
G03X232328Y180562I-1532J1532D01*
G01X232335Y180634D01*
X232954Y181253D01*
G37*
G36*
G01X267730Y135010D02*
X281530D01*
X285640Y130900D01*
Y120830D01*
X282750Y117940D01*
X268380D01*
X266140Y120180D01*
Y133420D01*
X267730Y135010D01*
G37*
G36*
G01X326827Y390261D02*
X342282D01*
X343210Y389333D01*
Y341844D01*
X338086Y336720D01*
Y287667D01*
G02X337397Y287391I-400J0D01*
G03X336312Y287854I-1085J-1040D01*
G03X334810Y286352I0J-1502D01*
G03X335547Y285059I1503J0D01*
G02X335563Y284406I-223J-332D01*
G03X334959Y283202I898J-1204D01*
G03X336461Y281700I1502J0D01*
G03X337438Y282061I0J1503D01*
G02X338086Y281747I248J-314D01*
G01Y279122D01*
X334192Y275228D01*
X316833D01*
X312133Y279928D01*
G02X312386Y280609I283J282D01*
G03X313774Y282107I-114J1498D01*
G03X312882Y283480I-1503J0D01*
G02X312744Y284110I162J366D01*
G03X313172Y285160I-1074J1050D01*
G03X312580Y286355I-1502J0D01*
G02X312666Y287042I242J319D01*
G03X313616Y288439I-552J1397D01*
G03X310612I-1502J0D01*
G03X311204Y287244I1502J0D01*
G02X311118Y286557I-242J-319D01*
G03X310168Y285160I552J-1397D01*
G03X311060Y283787I1503J0D01*
G02X311198Y283157I-162J-366D01*
G03X310777Y282252I1074J-1050D01*
G01X310774Y282221D01*
G02X310093Y281968I-399J30D01*
G01X309646Y282415D01*
Y287180D01*
G03X308789Y289249I-2926J0D01*
G01X305272Y292767D01*
X303736Y294303D01*
Y296169D01*
G03Y298869I-659J1350D01*
G01Y303103D01*
G02X304107Y303502I400J0D01*
G03Y306498I-107J1498D01*
G02X303736Y306897I29J399D01*
G01Y307891D01*
G03X304165Y308252I-736J1309D01*
G02X304838Y308168I310J-253D01*
G03X306200Y307298I1362J631D01*
G03Y310302I0J1502D01*
G03X305035Y309748I0J-1502D01*
G02X304362Y309832I-310J253D01*
G03X303268Y310678I-1363J-632D01*
G03X302878Y311160I-2457J-1590D01*
G01X301426Y312612D01*
Y320520D01*
G03X300569Y322589I-2926J0D01*
G01X300387Y322772D01*
X300307Y322852D01*
Y324771D01*
G02X300874Y325135I400J0D01*
G03X301500Y324998I627J1365D01*
G03Y328002I0J1502D01*
G03X300874Y327865I1J-1502D01*
G02X300307Y328229I-167J364D01*
G01Y339398D01*
G02X300706Y339798I400J0D01*
G03Y342802I-6J1502D01*
G02X300307Y343202I1J400D01*
G01Y386818D01*
X303750Y390261D01*
X323813D01*
X323818Y390094D01*
G03X326822I1502J24D01*
G01X326827Y390261D01*
G37*
G36*
G01X295187Y461587D02*
X299678D01*
X300086Y461179D01*
Y448087D01*
X302598Y445575D01*
X329773D01*
X332404Y442944D01*
Y433340D01*
G03X332386Y432809I8235J-545D01*
G03X332404Y432278I8253J14D01*
G01Y427596D01*
X337355Y422645D01*
Y405966D01*
X336756Y405367D01*
X316533D01*
X314050Y407850D01*
Y430353D01*
X307981Y436422D01*
X296239D01*
X294749Y437912D01*
Y461149D01*
X295187Y461587D01*
G37*
G36*
G01X314385Y467812D02*
X315625D01*
X315966Y467471D01*
Y453751D01*
X315647Y453432D01*
X314431D01*
X313969Y453894D01*
Y467396D01*
X314385Y467812D01*
G37*
%LPC*%
G75*
G36*
G01X22813Y128943D02*
G03Y129573I-246J315D01*
G02X22234Y130758I923J1185D01*
G02X25238I1502J0D01*
G02X24659Y129573I-1502J0D01*
G03Y128943I246J-315D01*
G02X25238Y127758I-923J-1185D01*
G02X22234I-1502J0D01*
G02X22813Y128943I1502J0D01*
G37*
G36*
G01X31313D02*
G03Y129573I-246J315D01*
G02X30734Y130758I923J1185D01*
G02X33738I1502J0D01*
G02X33159Y129573I-1502J0D01*
G03Y128943I246J-315D01*
G02X33738Y127758I-923J-1185D01*
G02X30734I-1502J0D01*
G02X31313Y128943I1502J0D01*
G37*
G36*
G01X39813D02*
G03Y129573I-246J315D01*
G02X39234Y130758I923J1185D01*
G02X42238I1502J0D01*
G02X41659Y129573I-1502J0D01*
G03Y128943I246J-315D01*
G02X42238Y127758I-923J-1185D01*
G02X39234I-1502J0D01*
G02X39813Y128943I1502J0D01*
G37*
G36*
G01X34677Y239385D02*
G03Y240015I-246J315D01*
G02X34098Y241200I923J1185D01*
G02X37102I1502J0D01*
G02X36523Y240015I-1502J0D01*
G03Y239385I246J-315D01*
G02X37102Y238200I-923J-1185D01*
G02X34098I-1502J0D01*
G02X34677Y239385I1502J0D01*
G37*
G36*
G01X38105Y302475D02*
G03Y303102I-249J314D01*
G02X37537Y304278I933J1176D01*
G02X40541I1502J0D01*
G02X39973Y303102I-1501J0D01*
G03Y302475I249J-313D01*
G02X40541Y301299I-933J-1176D01*
G02X37537I-1502J0D01*
G02X38105Y302475I1501J0D01*
G37*
G36*
G01X29956Y303264D02*
G02X29136Y304602I682J1338D01*
G02X32140I1502J0D01*
G02X31320Y303264I-1502J0D01*
G03Y302551I182J-357D01*
G02X32140Y301213I-682J-1338D01*
G02X29136I-1502J0D01*
G02X29956Y302551I1502J0D01*
G03Y303264I-182J356D01*
G37*
G36*
G01X21555Y303288D02*
G02X20735Y304626I682J1338D01*
G02X23739I1502J0D01*
G02X22919Y303288I-1502J0D01*
G03Y302575I182J-357D01*
G02X23739Y301237I-682J-1338D01*
G02X20735I-1502J0D01*
G02X21555Y302575I1502J0D01*
G03Y303288I-182J357D01*
G37*
G36*
G01X90435Y90930D02*
G03Y91560I-246J315D01*
G02X89856Y92745I923J1185D01*
G02X92860I1502J0D01*
G02X92281Y91560I-1502J0D01*
G03Y90930I246J-315D01*
G02Y88560I-923J-1185D01*
G03Y87930I246J-315D01*
G02Y85560I-923J-1185D01*
G03Y84930I246J-315D01*
G02X92860Y83745I-923J-1185D01*
G02X89856I-1502J0D01*
G02X90435Y84930I1502J0D01*
G03Y85560I-246J315D01*
G02X89856Y86745I923J1185D01*
G02X89869Y86945I1502J3D01*
G02X90440Y87934I1489J-200D01*
G03X90435Y88560I-251J311D01*
G02Y90930I923J1185D01*
G37*
G36*
G01X73834D02*
G03Y91560I-246J315D01*
G02X73255Y92745I923J1185D01*
G02X76259I1502J0D01*
G02X75680Y91560I-1502J0D01*
G03Y90930I246J-315D01*
G02Y88560I-923J-1185D01*
G03Y87930I246J-315D01*
G02Y85560I-923J-1185D01*
G03Y84930I246J-315D01*
G02X76259Y83745I-923J-1185D01*
G02X73255I-1502J0D01*
G02X73834Y84930I1502J0D01*
G03Y85560I-246J315D01*
G02X73255Y86745I923J1185D01*
G02X73268Y86945I1502J3D01*
G02X73839Y87934I1489J-200D01*
G03X73834Y88560I-251J311D01*
G02Y90930I923J1185D01*
G37*
G36*
G01X147687Y124184D02*
G03Y124710I-302J263D01*
G02X147317Y125697I1131J987D01*
G02X150321I1502J0D01*
G02X149951Y124710I-1501J0D01*
G03Y124184I302J-263D01*
G02X150321Y123197I-1131J-987D01*
G02X147317I-1502J0D01*
G02X147687Y124184I1501J0D01*
G37*
G36*
G01X186390Y130702D02*
G03X186375Y131291I-278J288D01*
G02X185858Y132425I985J1134D01*
G02X188862I1502J0D01*
G02X188405Y131346I-1502J0D01*
G03X188420Y130757I278J-288D01*
G02X188937Y129623I-985J-1134D01*
G02X185933I-1502J0D01*
G02X186390Y130702I1502J0D01*
G37*
G36*
G01X181293Y131029D02*
G02X180601Y132294I810J1265D01*
G02X183605I1502J0D01*
G02X182917Y131032I-1501J0D01*
G03X182918Y130359I217J-336D01*
G02X183610Y129094I-810J-1265D01*
G02X180606I-1502J0D01*
G02X181294Y130356I1501J0D01*
G03X181293Y131029I-217J336D01*
G37*
G36*
G01X186869Y160673D02*
X186970Y160756D01*
G02X187794Y161050I824J-1008D01*
G02X186492Y159748I0J-1302D01*
G02X186786Y160572I1302J0D01*
G01X186869Y160673D01*
G37*
G36*
G01X267872Y143463D02*
G02X267502Y144450I1131J987D01*
G02X270506I1502J0D01*
G02X270136Y143463I-1501J0D01*
G03Y142937I302J-263D01*
G02X270506Y141950I-1131J-987D01*
G02X269878Y140728I-1503J0D01*
G03X269981Y140025I233J-325D01*
G02X270995Y138604I-489J-1421D01*
G02X267991I-1502J0D01*
G02X268619Y139826I1503J0D01*
G03X268516Y140529I-233J325D01*
G02X267502Y141950I489J1421D01*
G02X267872Y142937I1501J0D01*
G03Y143463I-302J263D01*
G37*
G36*
G01X282248Y140925D02*
G03X281722Y140930I-266J-299D01*
G02X280744Y140568I-978J1140D01*
G02Y143572I0J1502D01*
G02X281744Y143191I0J-1503D01*
G03X282270Y143186I266J299D01*
G02X283248Y143548I978J-1140D01*
G02Y140544I0J-1502D01*
G02X282248Y140925I0J1503D01*
G37*
G36*
G01X275349Y124638D02*
G03X274821Y124436I-163J-365D01*
G02X273450Y123548I-1371J614D01*
G02Y126552I0J1502D01*
G02X274061Y126422I0J-1501D01*
G03X274589Y126624I163J365D01*
G02X275960Y127512I1371J-614D01*
G02Y124508I0J-1502D01*
G02X275349Y124638I0J1501D01*
G37*
G36*
G01X323911Y327035D02*
G03Y327581I-292J273D01*
G02X323505Y328608I1096J1027D01*
G02X325007Y330110I1502J0D01*
G02X326061Y329678I0J-1502D01*
G03X326628Y329683I281J285D01*
G02X327704Y330137I1076J-1048D01*
G02X329206Y328635I0J-1502D01*
G02X328800Y327608I-1502J0D01*
G03Y327062I292J-273D01*
G02X329206Y326035I-1096J-1027D01*
G02X328836Y325048I-1501J0D01*
G03Y324522I302J-263D01*
G02X329206Y323535I-1131J-987D01*
G02X327704Y322033I-1502J0D01*
G02X326650Y322465I0J1502D01*
G03X326083Y322460I-281J-285D01*
G02X325007Y322006I-1076J1048D01*
G02X323505Y323508I0J1502D01*
G02X323875Y324495I1501J0D01*
G03Y325021I-302J263D01*
G02X323505Y326008I1131J987D01*
G02X323911Y327035I1502J0D01*
G37*
G36*
G01X310270Y293399D02*
G02X309700Y293287I-569J1390D01*
G02Y296291I0J1502D01*
G02X311195Y294929I0J-1501D01*
G03X311745Y294597I398J38D01*
G02X312315Y294709I569J-1390D01*
G02Y291705I0J-1502D01*
G02X310820Y293067I0J1501D01*
G03X310270Y293399I-398J-38D01*
G37*
G36*
G01X313231Y301215D02*
G02X312699Y302361I970J1147D01*
G02X315703I1502J0D01*
G02X315155Y301201I-1502J0D01*
G03X315150Y300586I254J-310D01*
G02X315682Y299440I-970J-1147D01*
G02X315114Y298264I-1501J0D01*
G03X315249Y297567I249J-313D01*
G02X316039Y297006I-428J-1440D01*
G03X316588Y296909I324J234D01*
G02X317430Y297167I842J-1245D01*
G02X318932Y295665I0J-1502D01*
G02X317630Y294176I-1502J0D01*
G03X317289Y293711I53J-396D01*
G02X317312Y293450I-1479J-262D01*
G02X317309Y293356I-1502J1D01*
G03X317700Y292932I399J-24D01*
G02X319172Y291430I-30J-1502D01*
G02X316168I-1502J0D01*
G02X316171Y291524I1502J-1D01*
G03X315780Y291948I-399J24D01*
G02X314308Y293450I30J1502D01*
G02X314488Y294163I1502J0D01*
G03X314280Y294726I-352J190D01*
G02X313318Y296128I541J1402D01*
G02X313886Y297304I1501J0D01*
G03X313751Y298001I-249J313D01*
G02X312678Y299440I428J1439D01*
G02X313226Y300600I1502J0D01*
G03X313231Y301215I-254J310D01*
G37*
G36*
G01X313310Y308921D02*
G02X312630Y310178I822J1257D01*
G02X315634I1502J0D01*
G02X314984Y308941I-1502J0D01*
G03X314992Y308277I227J-329D01*
G02X315672Y307020I-822J-1257D01*
G02X312668I-1502J0D01*
G02X313318Y308257I1502J0D01*
G03X313310Y308921I-227J329D01*
G37*
G36*
G01X313175Y365643D02*
G02X311925Y364973I-1250J831D01*
G02Y367977I0J1502D01*
G02X313162Y367327I0J-1502D01*
G03X313825Y367332I330J227D01*
G02X315075Y368002I1250J-831D01*
G02Y364998I0J-1502D01*
G02X313838Y365648I0J1502D01*
G03X313175Y365643I-330J-227D01*
G37*
G36*
G01X325022Y382409D02*
G02X323698Y383900I178J1491D01*
G02X326702I1502J0D01*
G02X326306Y382883I-1502J-1D01*
G03X326553Y382215I294J-271D01*
G02X327877Y380724I-178J-1491D01*
G02X324873I-1502J0D01*
G02X325269Y381741I1502J1D01*
G03X325022Y382409I-294J271D01*
G37*
G54D21*
X39408Y195990D03*
X19100Y187420D03*
X24705Y258767D03*
X37485Y258807D03*
X86700Y119100D03*
X156286Y124903D03*
X178284Y132394D03*
X174553Y128728D03*
X178290Y128824D03*
X196577Y141185D03*
X176550Y125210D03*
X189700Y140400D03*
X161237Y181735D03*
X148400Y155765D03*
X153051Y187354D03*
X144500Y169570D03*
X152556Y147683D03*
X171700Y156900D03*
X151940Y203710D03*
X159000Y135000D03*
X162419Y131032D03*
X176000Y140500D03*
X172100Y146300D03*
X166700Y132360D03*
X287555Y142419D03*
X301936Y143897D03*
X292204Y142610D03*
X258500Y146400D03*
X274500Y131629D03*
X279600Y131400D03*
X280400Y126000D03*
X268435Y121476D03*
X314340Y373296D03*
X312226Y382766D03*
X325038Y356890D03*
X308500Y382100D03*
X312300Y340700D03*
X326100Y375717D03*
X326200Y370681D03*
X325900Y365643D03*
X335708Y372008D03*
X330900Y314700D03*
X335700Y376400D03*
X335500Y363200D03*
Y380000D03*
X334600Y383300D03*
X335475Y367500D03*
Y358500D03*
X311000Y320500D03*
X309500Y315000D03*
G54D22*
X206692Y156599D03*
X209842D03*
Y159748D03*
Y169197D03*
X212991D03*
X206692D03*
Y162898D03*
X209842D03*
X206692Y159748D03*
X212991Y162898D03*
X209842Y153449D03*
X212991Y166047D03*
X209842D03*
X206692D03*
X178346Y184945D03*
X181495Y181795D03*
Y184945D03*
X206692Y178646D03*
X209842Y181795D03*
Y184945D03*
X206692Y181795D03*
X187794D03*
X190944Y184945D03*
X187794D03*
X190944Y181795D03*
X184645D03*
Y184945D03*
X174569Y180202D03*
X197243Y184945D03*
X175196Y156599D03*
X178346Y172347D03*
Y162898D03*
X181495Y172347D03*
Y166047D03*
X184645Y169197D03*
Y166047D03*
Y172347D03*
X181495Y169197D03*
X175196Y159748D03*
X187794Y169197D03*
Y172347D03*
X178346Y159748D03*
X181495Y191244D03*
X174336Y192800D03*
X178346Y191244D03*
X219290Y191207D03*
X219253Y188095D03*
X222402Y191244D03*
X203542D03*
X206692D03*
X200393D03*
X197243D03*
X190944D03*
X184645D03*
X187794Y156599D03*
X200393Y169197D03*
X197243Y166047D03*
Y159748D03*
X194094D03*
X197243Y162898D03*
X200393D03*
Y166047D03*
X190944Y159748D03*
X184645Y153449D03*
X187794D03*
X203542Y210104D03*
Y206955D03*
X200393Y210104D03*
X197243Y203805D03*
X200393Y206955D03*
X197243Y200655D03*
X190944D03*
X203542D03*
X190944Y203805D03*
Y210104D03*
X235001Y156599D03*
X238150Y159748D03*
X235001Y178646D03*
Y175496D03*
Y159748D03*
Y162898D03*
X231851Y159748D03*
Y162898D03*
X235001Y166047D03*
X238150Y162898D03*
X231851Y156599D03*
X235001Y153449D03*
X238150Y156599D03*
%LPD*%
G75*
G54D10*
X-61709Y56192D03*
X-51709D03*
G54D20*
G01X253898Y232151D02*
X255368Y230681D01*
X257682D01*
X259100Y232099D01*
Y232691D01*
X260818Y234409D01*
G01X257048Y232151D02*
X258249Y233352D01*
Y233700D01*
X259932Y235383D01*
G01X250749Y229002D02*
X251819D01*
X253289Y227532D01*
X254732D01*
X254972Y227772D01*
X257338D01*
G01X253898Y229002D02*
X254998D01*
X255400Y228600D01*
X256762D01*
X257254Y229092D01*
X257338D01*
G54D11*
X3000Y8494D03*
Y28494D03*
Y48494D03*
Y68494D03*
Y88494D03*
Y108494D03*
Y128494D03*
Y148494D03*
Y168494D03*
Y188494D03*
Y208494D03*
Y228494D03*
Y248494D03*
Y268494D03*
Y288494D03*
Y308494D03*
Y342126D03*
Y362126D03*
Y382126D03*
Y402126D03*
Y422126D03*
Y442126D03*
X16626Y195848D03*
X19129D03*
Y193048D03*
X16626D03*
X19129Y204248D03*
X17000Y208017D03*
Y211541D03*
X16626Y198648D03*
Y201448D03*
X19129Y198648D03*
Y201448D03*
X16626Y204248D03*
X17000Y215713D03*
Y219288D03*
X18000Y240900D03*
Y237900D03*
Y249900D03*
Y246900D03*
Y243900D03*
X15688Y259063D03*
X13827Y325310D03*
X13869Y352239D03*
X14600Y422500D03*
X22218Y3000D03*
X23723Y123791D03*
Y120791D03*
X32223Y123791D03*
Y120791D03*
X31920Y186610D03*
X21250Y206220D03*
X21135Y236587D03*
X21205Y232767D03*
X21135Y240667D03*
Y243737D03*
X24690Y246467D03*
Y251967D03*
X21135Y246837D03*
X21035Y249937D03*
X24690Y249267D03*
X22237Y311481D03*
Y308592D03*
X30638Y311957D03*
Y309068D03*
X23677Y422419D03*
X20225Y447671D03*
X22692Y466518D03*
X42218Y3000D03*
X40340Y100710D03*
X40723Y123791D03*
Y120791D03*
X49223Y123791D03*
Y121291D03*
X47294Y184491D03*
X36599Y189016D03*
X37360Y194050D03*
X37823Y198346D03*
X48035Y191535D03*
X39900Y211000D03*
X48023Y217860D03*
X39567Y243133D03*
X40500Y236900D03*
X41574Y255937D03*
X46220Y277170D03*
X39039Y309044D03*
Y311933D03*
X39100Y321600D03*
X35500Y340500D03*
X44500Y348000D03*
X37735Y391200D03*
X44525Y391650D03*
X35101Y381610D03*
X44525Y394150D03*
X44341Y406480D03*
X39530Y409100D03*
X42900Y412900D03*
X42200Y435900D03*
X48050Y436350D03*
X45100Y435800D03*
X46100Y422800D03*
X40848Y448440D03*
X62218Y3000D03*
X50710Y54724D03*
X52410Y190190D03*
X64050Y201010D03*
X58000Y217700D03*
X51010Y233570D03*
X50700Y250400D03*
X60225Y336099D03*
X52765Y390200D03*
X52330Y413350D03*
X59511Y424477D03*
X60622Y431273D03*
X64122D03*
X56250Y424200D03*
X52750D03*
X56482Y456844D03*
Y453344D03*
X63569Y456844D03*
Y453344D03*
X72044Y132312D03*
X71970Y135893D03*
X69195Y135799D03*
X69285Y132321D03*
X68335Y141369D03*
X68375Y144100D03*
X68434Y149506D03*
X68432Y152147D03*
X72300Y159400D03*
X68600Y159160D03*
X73550Y166680D03*
X71124Y178565D03*
X67700Y229725D03*
X65755Y256045D03*
X76200Y247400D03*
X77384Y253769D03*
X68990Y260465D03*
X75300Y305150D03*
X73400Y313700D03*
X77500Y316100D03*
X71700Y340600D03*
X77592Y413437D03*
X72150Y424199D03*
X75650D03*
X82218Y3000D03*
X84500Y66500D03*
X90151Y68985D03*
X88500Y128000D03*
X89170Y141540D03*
X81800Y188500D03*
X90900Y222850D03*
X87500Y237300D03*
X80270Y247830D03*
X92300Y282100D03*
X81864Y297900D03*
X85600Y298100D03*
X82200Y308700D03*
X82022Y303350D03*
X84126Y311790D03*
X79600Y312000D03*
X85500Y326700D03*
X92698Y323224D03*
X93288Y330289D03*
X81900Y337100D03*
X87800Y410300D03*
X86481Y407871D03*
X96030Y409400D03*
X92801Y452793D03*
X102218Y3000D03*
X104600Y50501D03*
X107124Y71004D03*
X110950Y82050D03*
X106000Y91900D03*
X105916Y109952D03*
X101230Y127010D03*
X95950Y152900D03*
X95944Y149687D03*
X103500Y240619D03*
X95300Y247100D03*
X107200Y265000D03*
X106100Y282900D03*
X99990Y307900D03*
X94400Y311100D03*
Y307200D03*
X95060Y327625D03*
X105500Y418200D03*
X108701Y418300D03*
X98300Y407600D03*
X108336Y411547D03*
X104112Y422946D03*
X103461Y425875D03*
X95870Y445483D03*
X99370D03*
X96301Y452793D03*
X122218Y3000D03*
X112800Y60400D03*
X112600Y52800D03*
X109121Y69500D03*
X112000Y123500D03*
X109350Y115501D03*
X109200Y118500D03*
Y128500D03*
X118692Y137304D03*
X113590Y245170D03*
X116143Y230790D03*
X109800Y264928D03*
X111600Y262730D03*
X122957Y300991D03*
X123100Y295974D03*
X110565Y296331D03*
X122330Y364670D03*
X117410Y381350D03*
X123100Y390600D03*
X119026Y393332D03*
X112800Y421600D03*
X113000Y416200D03*
X133000Y59900D03*
X131528Y114271D03*
X133500Y146800D03*
X129810Y191310D03*
X124226Y225194D03*
X134358Y230069D03*
X138600Y295900D03*
X129800Y325800D03*
X136000Y341000D03*
X125174Y393916D03*
X137900Y399500D03*
X142218Y3000D03*
X145000Y90700D03*
X145185Y134214D03*
X142892Y136645D03*
X143269Y150456D03*
X150155Y145086D03*
X146300Y161010D03*
X140554Y168887D03*
X153200Y170990D03*
X140554Y171688D03*
X150619Y178646D03*
X145296Y188835D03*
X150005Y184973D03*
X149100Y189963D03*
X147800Y200789D03*
X152500Y199500D03*
X142702Y227817D03*
X147500Y289405D03*
X141890Y310570D03*
X141045Y355309D03*
X151265Y399500D03*
X162218Y3000D03*
X166200Y105500D03*
X156406Y129203D03*
X153954Y145086D03*
X159900Y155600D03*
X161240Y177820D03*
X165500Y236100D03*
X164500Y266000D03*
X168392Y298493D03*
X170800Y317600D03*
X158459Y340898D03*
X161154Y376704D03*
X159050Y387334D03*
X162550D03*
X182218Y3000D03*
X169700Y102250D03*
X171600Y114000D03*
X182865Y113706D03*
X169100Y113900D03*
X169500Y180200D03*
X174400Y251936D03*
X172977Y277000D03*
X182435Y281797D03*
X179217Y278528D03*
X170550Y304050D03*
X171098Y341224D03*
X182700Y342216D03*
X178850Y385634D03*
X182350D03*
X191693Y236370D03*
X187400Y255700D03*
X185000Y270700D03*
X183625Y273500D03*
X196443Y294065D03*
X195031Y307182D03*
X197155Y314223D03*
X190600Y337900D03*
X183800Y345400D03*
X197711Y349250D03*
X195000Y373900D03*
X187300Y384300D03*
X195800Y396780D03*
X185245Y417500D03*
X202218Y3000D03*
X209142Y53664D03*
X208500Y126057D03*
X203542Y213254D03*
X206051Y247911D03*
X214034Y261482D03*
X200300Y328800D03*
X213200Y399166D03*
X213225Y442220D03*
X222218Y3000D03*
X214306Y62233D03*
X227760Y82524D03*
X224958Y107236D03*
X222890Y101240D03*
X221000Y243000D03*
X220100Y237200D03*
X223800Y254800D03*
X227316Y256700D03*
X215100Y244100D03*
X215500Y247111D03*
X216800Y255550D03*
X215510Y253310D03*
X225275Y246000D03*
X217500Y264000D03*
X219900Y267100D03*
X228800Y312100D03*
X225650Y337520D03*
X214175Y333740D03*
X228230Y340040D03*
X226710Y364815D03*
X223420Y367080D03*
X217390Y401340D03*
X217725Y410150D03*
X221225D03*
X217100Y436100D03*
X216725Y442220D03*
X242218Y3000D03*
X230293Y117417D03*
X234900Y126100D03*
X242195Y141003D03*
X237700Y257387D03*
X242690Y255300D03*
X230000Y255700D03*
X239298Y268800D03*
X242940Y268500D03*
X242087Y271427D03*
X238531Y263081D03*
X236688Y311217D03*
X230445Y325945D03*
X231689Y334896D03*
X231500Y352500D03*
X232470Y382280D03*
X249475Y55812D03*
X255213Y106099D03*
X249988Y105792D03*
X246488D03*
X253100Y119900D03*
X245500Y127800D03*
X245520Y130600D03*
X249300Y237600D03*
X247470Y269990D03*
X257145Y279700D03*
X247923Y316400D03*
X257900Y312100D03*
X253320Y323327D03*
X243700Y372730D03*
X244790Y375910D03*
X248800Y385700D03*
X262218Y3000D03*
X259000Y47500D03*
X263102Y91725D03*
X258713Y106099D03*
X264989Y101732D03*
X271602Y121400D03*
X269561Y130987D03*
X271300Y132900D03*
X258475Y254872D03*
X262700Y265100D03*
X262100Y280700D03*
X261500Y290440D03*
X264265Y315817D03*
X282218Y3000D03*
X286000Y47000D03*
X279800Y72700D03*
X283500Y126000D03*
X280616Y150971D03*
X283616D03*
X302218Y3000D03*
X299138Y244513D03*
X295729Y453912D03*
Y456912D03*
Y459912D03*
X297738Y452418D03*
Y458418D03*
Y455418D03*
X306500Y301500D03*
X308906Y362637D03*
X314969Y456527D03*
X322218Y3000D03*
X327162Y278972D03*
X329925Y356016D03*
X331500Y383300D03*
X325593Y406500D03*
X329093D03*
X318593D03*
X322093D03*
X331646Y466536D03*
X342218Y3000D03*
X342604Y318773D03*
X334112Y447668D03*
X351331Y20788D03*
Y40788D03*
Y60788D03*
Y80788D03*
Y100788D03*
Y120788D03*
Y140788D03*
Y160788D03*
Y180788D03*
Y200788D03*
Y220788D03*
Y240788D03*
Y260788D03*
Y280788D03*
Y300788D03*
X349290Y337646D03*
X351331Y357531D03*
Y377531D03*
Y397531D03*
Y417531D03*
Y437531D03*
X375876Y-159873D03*
X375964Y12313D03*
X375904Y68399D03*
X375964Y381585D03*
X379276Y-159873D03*
X379364Y12313D03*
X379304Y68399D03*
X379364Y381585D03*
G54D12*
G01X131528Y114271D02*
Y113680D01*
X138019Y107189D01*
Y95736D01*
X139819Y93936D01*
X148277D01*
X163249Y78964D01*
X204560D01*
X210175Y73349D01*
Y66364D01*
X214306Y62233D01*
G01X166200Y105500D02*
Y111000D01*
X169100Y113900D01*
G01X195000Y373900D02*
X183100Y362000D01*
Y353950D01*
X180673Y351523D01*
G01X259000Y47500D02*
Y51900D01*
X279800Y72700D01*
X62458Y343275D03*
Y355873D03*
X58564Y354280D03*
X65607Y352724D03*
X75056Y346425D03*
X68757D03*
X78206Y359023D03*
X75056Y352724D03*
Y349574D03*
Y374733D03*
X68757Y377883D03*
X65607Y381033D03*
X71906Y377883D03*
X81355D03*
X90766Y384182D03*
X92360Y394175D03*
X106515Y352724D03*
X106514Y349574D03*
X93916Y387332D03*
X178346Y210104D03*
X181495Y203805D03*
Y206955D03*
X175196Y210104D03*
X178346Y206955D03*
X175196D03*
Y203805D03*
X181495Y200655D03*
X175196Y213254D03*
X181495Y225852D03*
Y222703D03*
Y216403D03*
X175196Y229002D03*
X187794Y178646D03*
X190944Y172347D03*
Y175496D03*
X197243D03*
X187794D03*
Y197506D03*
Y200655D03*
X184645Y203805D03*
X187794Y219553D03*
X190944Y222702D03*
X184645Y225852D03*
Y222703D03*
X194094Y219553D03*
X206692Y175496D03*
X209842D03*
X200393D03*
Y213254D03*
X212991Y222740D03*
X206692Y219553D03*
X203542Y225852D03*
X206692Y229002D03*
X212991D03*
X206692Y225852D03*
X209746Y235397D03*
X200393Y232151D03*
X206692D03*
X225552Y159748D03*
X219253Y156599D03*
X225552Y181795D03*
X214547Y174852D03*
X225552Y219553D03*
X222402D03*
Y229002D03*
X222440Y225852D03*
X231851Y166047D03*
X238150D03*
X228702D03*
X231851Y169197D03*
Y178646D03*
X235001Y169197D03*
X241338Y225890D03*
X241300Y229002D03*
X239870Y237596D03*
X242870D03*
X235038Y229039D03*
X257048Y172347D03*
X250749Y178646D03*
X247599Y172347D03*
Y178646D03*
X244450D03*
Y172347D03*
X250749Y184945D03*
X247599Y191244D03*
X257048Y197506D03*
X253898D03*
X250749D03*
X244450Y188095D03*
X250749Y191244D03*
Y203805D03*
X247599Y200655D03*
X257048Y206955D03*
X250749Y200655D03*
X257048D03*
X247637Y225852D03*
X253898Y232151D03*
X257048D03*
X250749Y229002D03*
X253898D03*
X250749Y235301D03*
X253898D03*
X264118Y188095D03*
X266080Y207262D03*
X262580D03*
X282975Y172975D03*
X289254Y194839D03*
X289110Y163487D03*
X295410Y172936D03*
X289254Y172792D03*
X292384Y172936D03*
X292260Y179235D03*
X292404Y191690D03*
X289254D03*
X292404Y185534D03*
Y194983D03*
X295410Y194839D03*
X299667Y201334D03*
X314930Y171289D03*
X311158Y169643D03*
X308152Y176085D03*
Y179235D03*
X308008Y191690D03*
X311158D03*
X308008Y188540D03*
Y198133D03*
G54D13*
X441000Y-323400D03*
X451000D03*
Y-245000D03*
X441000D03*
Y126000D03*
X451000D03*
Y200000D03*
X441000D03*
G54D14*
G01X185450Y233950D02*
X184700Y234700D01*
X183000D01*
X181600Y236100D01*
Y238700D01*
X178000Y242300D01*
X171900D01*
X165700Y248500D01*
Y251300D01*
X167500Y253100D01*
Y256800D01*
X162700Y261600D01*
Y264900D01*
X163700Y265900D01*
X164400D01*
X164500Y266000D01*
G54D15*
G01X81800Y188500D02*
X83100Y187200D01*
Y178872D01*
X86230Y171316D01*
X101160Y156386D01*
Y144427D01*
X98800Y142067D01*
Y129440D01*
X101230Y127010D01*
G01X90900Y222850D02*
Y208000D01*
X92628Y206272D01*
Y181768D01*
X93019Y179804D01*
X94328Y176642D01*
X110650Y160320D01*
Y141750D01*
X112800Y139600D01*
Y124300D01*
X112000Y123500D01*
G01X87500Y237300D02*
Y234860D01*
X81060Y228420D01*
Y200060D01*
X79860Y198860D01*
Y196196D01*
X83138Y192918D01*
Y189838D01*
X81800Y188500D01*
G01X113590Y245170D02*
Y242610D01*
X115889Y240311D01*
Y234789D01*
X108490Y227390D01*
X95440D01*
X90900Y222850D01*
G01X87500Y237300D02*
X90820Y240620D01*
X103499D01*
X103500Y240619D01*
G01X112000Y123500D02*
X112700Y122800D01*
Y111799D01*
X110853Y109952D01*
X105916D01*
G01D02*
X104455Y111413D01*
Y123089D01*
X101230Y126314D01*
Y127010D01*
G01X113590Y245170D02*
Y245670D01*
X115645Y247725D01*
Y261721D01*
X113923Y265877D01*
X109800Y270000D01*
X101750D01*
X100250Y268500D01*
Y265250D01*
X102320Y263180D01*
Y244650D01*
X103500Y243470D01*
Y240619D01*
G01X172977Y277000D02*
X174550Y275427D01*
Y269126D01*
X182900Y260776D01*
Y258200D01*
X182200Y256510D01*
Y247799D01*
X187399Y242600D01*
X191000D01*
X196249Y237351D01*
X198093D01*
X200393Y235051D01*
Y232151D01*
G01X180673Y351523D02*
X171098Y341948D01*
Y341224D01*
G01X180673Y351523D02*
X182777D01*
X186700Y347600D01*
Y342414D01*
X190600Y338514D01*
Y337900D01*
G01X187300Y384300D02*
X188400D01*
X191500Y381200D01*
X198800D01*
X203400Y376600D01*
Y358400D01*
X195100Y350100D01*
Y345640D01*
X196600Y344140D01*
X198560D01*
X203600Y339100D01*
Y306410D01*
X201890Y304700D01*
X196900D01*
X195031Y306569D01*
Y307182D01*
G01X187300Y384300D02*
Y395700D01*
X183300Y399700D01*
Y415999D01*
X184801Y417500D01*
X185245D01*
G01X223800Y254800D02*
Y255161D01*
X223335Y255626D01*
Y257065D01*
X217500Y262900D01*
Y264000D01*
G54D16*
G01X2010999Y-388000D02*
Y1475775D01*
X-407000D01*
Y-386798D01*
Y-755294D01*
Y-793716D01*
X-368578D01*
X1942346D01*
X2010999D01*
Y-725063D01*
Y-388000D01*
G01X-53307Y-609436D02*
Y-684436D01*
X446693D01*
Y-609436D01*
X-53307D01*
G01X-41307Y-674436D02*
Y-679436D01*
G01X-42764Y-674436D02*
X-39850D01*
G01X-34940Y-679436D02*
X-37474D01*
Y-674436D01*
X-34940D01*
G01X-35954Y-676853D02*
X-37474D01*
G01X-32374Y-674436D02*
Y-679436D01*
X-29840D01*
G01X-26007Y-679603D02*
X-26134Y-679519D01*
Y-679353D01*
X-26007Y-679269D01*
X-25880Y-679353D01*
Y-679519D01*
X-26007Y-679603D01*
G01Y-677353D02*
X-26134Y-677269D01*
Y-677103D01*
X-26007Y-677019D01*
X-25880Y-677103D01*
Y-677269D01*
X-26007Y-677353D01*
G01X-21224Y-681103D02*
X-21857Y-680269D01*
X-22174Y-679436D01*
Y-676103D01*
X-21857Y-675269D01*
X-21224Y-674436D01*
G01X-15807D02*
X-16314Y-674603D01*
X-16694Y-675019D01*
X-16947Y-675519D01*
X-17137Y-676186D01*
X-17200Y-676936D01*
X-17137Y-677686D01*
X-16947Y-678353D01*
X-16694Y-678853D01*
X-16314Y-679269D01*
X-15807Y-679436D01*
X-15300Y-679269D01*
X-14920Y-678853D01*
X-14667Y-678353D01*
X-14477Y-677686D01*
X-14414Y-676936D01*
X-14477Y-676186D01*
X-14667Y-675519D01*
X-14920Y-675019D01*
X-15300Y-674603D01*
X-15807Y-674436D01*
G01X-12100Y-678436D02*
X-11720Y-679019D01*
X-11214Y-679353D01*
X-10644Y-679436D01*
X-10137Y-679353D01*
X-9630Y-678936D01*
X-9314Y-678436D01*
X-9250Y-677936D01*
X-9377Y-677353D01*
X-9820Y-676936D01*
X-10264Y-676769D01*
X-10834D01*
G01X-10264D02*
X-9884Y-676519D01*
X-9567Y-676103D01*
X-9440Y-675603D01*
X-9567Y-675103D01*
X-9884Y-674686D01*
X-10454Y-674436D01*
X-11024Y-674519D01*
X-11594Y-674853D01*
G01X-5290Y-681103D02*
X-4657Y-680269D01*
X-4340Y-679436D01*
Y-676103D01*
X-4657Y-675269D01*
X-5290Y-674436D01*
G01X-1900Y-678436D02*
X-1520Y-679019D01*
X-1014Y-679353D01*
X-444Y-679436D01*
X63Y-679353D01*
X570Y-678936D01*
X886Y-678436D01*
X950Y-677936D01*
X823Y-677353D01*
X380Y-676936D01*
X-64Y-676769D01*
X-634D01*
G01X-64D02*
X316Y-676519D01*
X633Y-676103D01*
X760Y-675603D01*
X633Y-675103D01*
X316Y-674686D01*
X-254Y-674436D01*
X-824Y-674519D01*
X-1394Y-674853D01*
G01X3390Y-675269D02*
X3770Y-674769D01*
X4213Y-674519D01*
X4720Y-674436D01*
X5353Y-674603D01*
X5796Y-675019D01*
X5923Y-675519D01*
X5860Y-676019D01*
X5606Y-676436D01*
X4340Y-677269D01*
X3770Y-677853D01*
X3390Y-678686D01*
X3263Y-679436D01*
X5923D01*
G01X9566D02*
X9693Y-678353D01*
X9883Y-677436D01*
X10136Y-676603D01*
X10453Y-675686D01*
X10960Y-674436D01*
X8426D01*
G01X13970Y-677769D02*
X15616D01*
G01X18690Y-675269D02*
X19070Y-674769D01*
X19513Y-674519D01*
X20020Y-674436D01*
X20653Y-674603D01*
X21096Y-675019D01*
X21223Y-675519D01*
X21160Y-676019D01*
X20906Y-676436D01*
X19640Y-677269D01*
X19070Y-677853D01*
X18690Y-678686D01*
X18563Y-679436D01*
X21223D01*
G01X23600Y-678436D02*
X23980Y-679019D01*
X24486Y-679353D01*
X25056Y-679436D01*
X25563Y-679353D01*
X26070Y-678936D01*
X26386Y-678436D01*
X26450Y-677936D01*
X26323Y-677353D01*
X25880Y-676936D01*
X25436Y-676769D01*
X24866D01*
G01X25436D02*
X25816Y-676519D01*
X26133Y-676103D01*
X26260Y-675603D01*
X26133Y-675103D01*
X25816Y-674686D01*
X25246Y-674436D01*
X24676Y-674519D01*
X24106Y-674853D01*
G01X30853Y-679436D02*
Y-674436D01*
X28510Y-678019D01*
X31676D01*
G01X33800Y-678686D02*
X34180Y-679103D01*
X34623Y-679353D01*
X35193Y-679436D01*
X35763Y-679269D01*
X36206Y-678936D01*
X36523Y-678353D01*
X36586Y-677686D01*
X36460Y-677019D01*
X36143Y-676603D01*
X35700Y-676269D01*
X35256Y-676186D01*
X34813Y-676269D01*
X34243Y-676603D01*
X34433Y-674436D01*
X36143D01*
G01X44190Y-679436D02*
Y-674436D01*
X46596D01*
G01X45710Y-676853D02*
X44190D01*
G01X48910Y-679436D02*
X50493Y-674436D01*
X52076Y-679436D01*
G01X51506Y-677686D02*
X49480D01*
G01X54263Y-679436D02*
X56923Y-674436D01*
G01X54263D02*
X56923Y-679436D01*
G01X60693Y-679603D02*
X60566Y-679519D01*
Y-679353D01*
X60693Y-679269D01*
X60820Y-679353D01*
Y-679519D01*
X60693Y-679603D01*
G01Y-677353D02*
X60566Y-677269D01*
Y-677103D01*
X60693Y-677019D01*
X60820Y-677103D01*
Y-677269D01*
X60693Y-677353D01*
G01X65476Y-681103D02*
X64843Y-680269D01*
X64526Y-679436D01*
Y-676103D01*
X64843Y-675269D01*
X65476Y-674436D01*
G01X70893D02*
X70386Y-674603D01*
X70006Y-675019D01*
X69753Y-675519D01*
X69563Y-676186D01*
X69500Y-676936D01*
X69563Y-677686D01*
X69753Y-678353D01*
X70006Y-678853D01*
X70386Y-679269D01*
X70893Y-679436D01*
X71400Y-679269D01*
X71780Y-678853D01*
X72033Y-678353D01*
X72223Y-677686D01*
X72286Y-676936D01*
X72223Y-676186D01*
X72033Y-675519D01*
X71780Y-675019D01*
X71400Y-674603D01*
X70893Y-674436D01*
G01X74600Y-678436D02*
X74980Y-679019D01*
X75486Y-679353D01*
X76056Y-679436D01*
X76563Y-679353D01*
X77070Y-678936D01*
X77386Y-678436D01*
X77450Y-677936D01*
X77323Y-677353D01*
X76880Y-676936D01*
X76436Y-676769D01*
X75866D01*
G01X76436D02*
X76816Y-676519D01*
X77133Y-676103D01*
X77260Y-675603D01*
X77133Y-675103D01*
X76816Y-674686D01*
X76246Y-674436D01*
X75676Y-674519D01*
X75106Y-674853D01*
G01X81410Y-681103D02*
X82043Y-680269D01*
X82360Y-679436D01*
Y-676103D01*
X82043Y-675269D01*
X81410Y-674436D01*
G01X84800Y-678436D02*
X85180Y-679019D01*
X85686Y-679353D01*
X86256Y-679436D01*
X86763Y-679353D01*
X87270Y-678936D01*
X87586Y-678436D01*
X87650Y-677936D01*
X87523Y-677353D01*
X87080Y-676936D01*
X86636Y-676769D01*
X86066D01*
G01X86636D02*
X87016Y-676519D01*
X87333Y-676103D01*
X87460Y-675603D01*
X87333Y-675103D01*
X87016Y-674686D01*
X86446Y-674436D01*
X85876Y-674519D01*
X85306Y-674853D01*
G01X90216Y-678853D02*
X90660Y-679269D01*
X91166Y-679436D01*
X91673Y-679269D01*
X92116Y-678769D01*
X92433Y-678019D01*
X92560Y-677269D01*
Y-676353D01*
X92433Y-675603D01*
X92116Y-674936D01*
X91736Y-674603D01*
X91293Y-674436D01*
X90786Y-674603D01*
X90406Y-674936D01*
X90153Y-675436D01*
X90026Y-676103D01*
X90153Y-676686D01*
X90470Y-677269D01*
X90850Y-677603D01*
X91293Y-677686D01*
X91800Y-677519D01*
X92180Y-677103D01*
X92560Y-676353D01*
G01X96266Y-679436D02*
X96393Y-678353D01*
X96583Y-677436D01*
X96836Y-676603D01*
X97153Y-675686D01*
X97660Y-674436D01*
X95126D01*
G01X100670Y-677769D02*
X102316D01*
G01X105200Y-678436D02*
X105580Y-679019D01*
X106086Y-679353D01*
X106656Y-679436D01*
X107163Y-679353D01*
X107670Y-678936D01*
X107986Y-678436D01*
X108050Y-677936D01*
X107923Y-677353D01*
X107480Y-676936D01*
X107036Y-676769D01*
X106466D01*
G01X107036D02*
X107416Y-676519D01*
X107733Y-676103D01*
X107860Y-675603D01*
X107733Y-675103D01*
X107416Y-674686D01*
X106846Y-674436D01*
X106276Y-674519D01*
X105706Y-674853D01*
G01X110490Y-677353D02*
X110933Y-676769D01*
X111313Y-676436D01*
X111820Y-676269D01*
X112263Y-676436D01*
X112580Y-676769D01*
X112833Y-677269D01*
X112896Y-677853D01*
X112833Y-678353D01*
X112580Y-678853D01*
X112200Y-679269D01*
X111756Y-679436D01*
X111250Y-679269D01*
X110806Y-678769D01*
X110553Y-678019D01*
X110490Y-677186D01*
X110616Y-676103D01*
X110806Y-675519D01*
X111123Y-674936D01*
X111566Y-674519D01*
X112010Y-674436D01*
X112453Y-674603D01*
X112770Y-675019D01*
G01X116793Y-679436D02*
Y-674436D01*
X116033Y-675436D01*
G01Y-679436D02*
X117553D01*
G01X122653D02*
Y-674436D01*
X120310Y-678019D01*
X123476D01*
G01X141693Y-609436D02*
Y-684436D01*
G01Y-659436D02*
X244693D01*
Y-634436D01*
G01X141693D02*
X244693D01*
G01X246693Y-609436D02*
Y-684436D01*
G01X244693Y-609436D02*
Y-684436D01*
G01X252200Y-669436D02*
Y-664436D01*
X253466D01*
X253973Y-664686D01*
X254353Y-665019D01*
X254670Y-665519D01*
X254923Y-666103D01*
X254986Y-666936D01*
X254923Y-667769D01*
X254670Y-668353D01*
X254353Y-668853D01*
X253973Y-669186D01*
X253466Y-669436D01*
X252200D01*
G01X257110D02*
X258693Y-664436D01*
X260276Y-669436D01*
G01X259706Y-667686D02*
X257680D01*
G01X263793Y-664436D02*
Y-669436D01*
G01X262336Y-664436D02*
X265250D01*
G01X270160Y-669436D02*
X267626D01*
Y-664436D01*
X270160D01*
G01X269146Y-666853D02*
X267626D01*
G01X273993Y-669603D02*
X273866Y-669519D01*
Y-669353D01*
X273993Y-669269D01*
X274120Y-669353D01*
Y-669519D01*
X273993Y-669603D01*
G01Y-667353D02*
X273866Y-667269D01*
Y-667103D01*
X273993Y-667019D01*
X274120Y-667103D01*
Y-667269D01*
X273993Y-667353D01*
G01X246693Y-659436D02*
X446693D01*
G01X252326Y-644436D02*
Y-639436D01*
X253846D01*
X254353Y-639686D01*
X254733Y-640269D01*
X254860Y-640936D01*
X254733Y-641603D01*
X254416Y-642103D01*
X253846Y-642353D01*
X252326D01*
G01X257553Y-644603D02*
X259833Y-639436D01*
G01X262336Y-644436D02*
Y-639436D01*
X265250Y-644436D01*
Y-639436D01*
G01X268893Y-644603D02*
X268766Y-644519D01*
Y-644353D01*
X268893Y-644269D01*
X269020Y-644353D01*
Y-644519D01*
X268893Y-644603D01*
G01Y-642353D02*
X268766Y-642269D01*
Y-642103D01*
X268893Y-642019D01*
X269020Y-642103D01*
Y-642269D01*
X268893Y-642353D01*
G01X246693Y-634436D02*
X446693D01*
G01X252326Y-619436D02*
Y-614436D01*
X253846D01*
X254353Y-614686D01*
X254733Y-615269D01*
X254860Y-615936D01*
X254733Y-616603D01*
X254416Y-617103D01*
X253846Y-617353D01*
X252326D01*
G01X257426Y-619436D02*
Y-614436D01*
X259010D01*
X259516Y-614686D01*
X259833Y-615019D01*
X259960Y-615686D01*
X259833Y-616353D01*
X259453Y-616769D01*
X259010Y-617019D01*
X257426D01*
G01X259010D02*
X259960Y-619436D01*
G01X263793D02*
X263286Y-619353D01*
X262843Y-619019D01*
X262463Y-618519D01*
X262210Y-617936D01*
X262083Y-617269D01*
Y-616603D01*
X262210Y-615936D01*
X262463Y-615353D01*
X262843Y-614853D01*
X263286Y-614519D01*
X263793Y-614436D01*
X264300Y-614519D01*
X264743Y-614853D01*
X265123Y-615353D01*
X265376Y-615936D01*
X265503Y-616603D01*
Y-617269D01*
X265376Y-617936D01*
X265123Y-618519D01*
X264743Y-619019D01*
X264300Y-619353D01*
X263793Y-619436D01*
G01X267626Y-618436D02*
X267943Y-618936D01*
X268323Y-619269D01*
X268766Y-619436D01*
X269273Y-619269D01*
X269653Y-618936D01*
X270033Y-618436D01*
X270160Y-617769D01*
Y-614436D01*
G01X275260Y-619436D02*
X272726D01*
Y-614436D01*
X275260D01*
G01X274246Y-616853D02*
X272726D01*
G01X280486Y-614853D02*
X280106Y-614603D01*
X279663Y-614436D01*
X279156D01*
X278586Y-614686D01*
X278143Y-615103D01*
X277826Y-615603D01*
X277573Y-616436D01*
X277510Y-617186D01*
X277636Y-617936D01*
X277826Y-618436D01*
X278206Y-618936D01*
X278650Y-619269D01*
X279093Y-619436D01*
X279536D01*
X279980Y-619269D01*
X280360Y-619019D01*
X280676Y-618686D01*
G01X284193Y-614436D02*
Y-619436D01*
G01X282736Y-614436D02*
X285650D01*
G01X289293Y-619603D02*
X289166Y-619519D01*
Y-619353D01*
X289293Y-619269D01*
X289420Y-619353D01*
Y-619519D01*
X289293Y-619603D01*
G01Y-617353D02*
X289166Y-617269D01*
Y-617103D01*
X289293Y-617019D01*
X289420Y-617103D01*
Y-617269D01*
X289293Y-617353D01*
G01X361693Y-659436D02*
Y-684436D01*
G01X364326Y-661936D02*
Y-666936D01*
X366860D01*
G01X369933Y-661936D02*
X371453D01*
G01X370693D02*
Y-666936D01*
G01X369933D02*
X371453D01*
G01X376300Y-664269D02*
X376553Y-664019D01*
X376743Y-663603D01*
X376870Y-663019D01*
X376743Y-662519D01*
X376490Y-662186D01*
X376046Y-661936D01*
X374336D01*
Y-666936D01*
X376426D01*
X376870Y-666603D01*
X377123Y-666103D01*
X377250Y-665519D01*
X377123Y-664936D01*
X376743Y-664436D01*
X376300Y-664269D01*
X374336D01*
G01X380893Y-667103D02*
X380766Y-667019D01*
Y-666853D01*
X380893Y-666769D01*
X381020Y-666853D01*
Y-667019D01*
X380893Y-667103D01*
G01Y-664853D02*
X380766Y-664769D01*
Y-664603D01*
X380893Y-664519D01*
X381020Y-664603D01*
Y-664769D01*
X380893Y-664853D01*
G01X404693Y-659436D02*
Y-684436D01*
G01Y-634436D02*
Y-659436D01*
G01X412706Y-687603D02*
X412813Y-687478D01*
X412893Y-687269D01*
X412946Y-686978D01*
X412893Y-686728D01*
X412786Y-686561D01*
X412600Y-686436D01*
X411880D01*
Y-688936D01*
X412760D01*
X412946Y-688769D01*
X413053Y-688519D01*
X413106Y-688228D01*
X413053Y-687936D01*
X412893Y-687686D01*
X412706Y-687603D01*
X411880D01*
G01X415173Y-688936D02*
Y-687269D01*
G01Y-687561D02*
X415066Y-687394D01*
X414906Y-687311D01*
X414720Y-687269D01*
X414533Y-687353D01*
X414373Y-687519D01*
X414266Y-687769D01*
X414213Y-688103D01*
X414266Y-688436D01*
X414373Y-688686D01*
X414533Y-688853D01*
X414720Y-688936D01*
X414906Y-688894D01*
X415066Y-688769D01*
X415173Y-688603D01*
G01X416493Y-688644D02*
X416626Y-688811D01*
X416813Y-688936D01*
X416973D01*
X417133Y-688853D01*
X417240Y-688728D01*
X417293Y-688561D01*
X417266Y-688311D01*
X417160Y-688186D01*
X416680Y-687936D01*
X416573Y-687644D01*
X416626Y-687436D01*
X416733Y-687311D01*
X416893Y-687269D01*
X417053Y-687311D01*
X417213Y-687436D01*
G01X418693Y-687811D02*
X419546D01*
X419466Y-687519D01*
X419333Y-687353D01*
X419146Y-687269D01*
X418960Y-687311D01*
X418800Y-687436D01*
X418693Y-687728D01*
X418640Y-687978D01*
Y-688228D01*
X418693Y-688478D01*
X418826Y-688728D01*
X418986Y-688894D01*
X419173Y-688936D01*
X419360Y-688853D01*
X419546Y-688603D01*
G01X420813Y-688936D02*
Y-686436D01*
G01Y-687686D02*
X420946Y-687436D01*
X421106Y-687311D01*
X421266Y-687269D01*
X421506Y-687353D01*
X421666Y-687519D01*
X421773Y-687811D01*
Y-688144D01*
X421720Y-688478D01*
X421613Y-688728D01*
X421426Y-688894D01*
X421266Y-688936D01*
X421106Y-688894D01*
X420946Y-688769D01*
X420813Y-688561D01*
G01X423493Y-688936D02*
X423333Y-688894D01*
X423173Y-688728D01*
X423066Y-688436D01*
X423013Y-688103D01*
X423066Y-687769D01*
X423173Y-687478D01*
X423333Y-687311D01*
X423493Y-687269D01*
X423653Y-687311D01*
X423813Y-687478D01*
X423920Y-687769D01*
X423946Y-688103D01*
X423920Y-688436D01*
X423813Y-688728D01*
X423653Y-688894D01*
X423493Y-688936D01*
G01X426173D02*
Y-687269D01*
G01Y-687561D02*
X426066Y-687394D01*
X425906Y-687311D01*
X425720Y-687269D01*
X425533Y-687353D01*
X425373Y-687519D01*
X425266Y-687769D01*
X425213Y-688103D01*
X425266Y-688436D01*
X425373Y-688686D01*
X425533Y-688853D01*
X425720Y-688936D01*
X425906Y-688894D01*
X426066Y-688769D01*
X426173Y-688603D01*
G01X427520Y-688936D02*
Y-687269D01*
G01Y-687603D02*
X427653Y-687436D01*
X427786Y-687311D01*
X427973Y-687269D01*
X428106Y-687311D01*
X428266Y-687436D01*
G01X430573Y-686436D02*
Y-688936D01*
G01Y-688561D02*
X430466Y-688769D01*
X430306Y-688894D01*
X430120Y-688936D01*
X429906Y-688853D01*
X429746Y-688644D01*
X429640Y-688394D01*
X429613Y-688103D01*
X429640Y-687811D01*
X429746Y-687561D01*
X429906Y-687353D01*
X430120Y-687269D01*
X430306Y-687311D01*
X430440Y-687394D01*
X430573Y-687561D01*
G01X433960Y-688936D02*
Y-686436D01*
X434626D01*
X434840Y-686561D01*
X434973Y-686728D01*
X435026Y-687061D01*
X434973Y-687394D01*
X434813Y-687603D01*
X434626Y-687728D01*
X433960D01*
G01X434626D02*
X435026Y-688936D01*
G01X436293Y-687811D02*
X437146D01*
X437066Y-687519D01*
X436933Y-687353D01*
X436746Y-687269D01*
X436560Y-687311D01*
X436400Y-687436D01*
X436293Y-687728D01*
X436240Y-687978D01*
Y-688228D01*
X436293Y-688478D01*
X436426Y-688728D01*
X436586Y-688894D01*
X436773Y-688936D01*
X436960Y-688853D01*
X437146Y-688603D01*
G01X438413Y-687269D02*
X438893Y-688936D01*
X439373Y-687269D01*
G01X441093Y-689019D02*
X441040Y-688978D01*
Y-688894D01*
X441093Y-688853D01*
X441146Y-688894D01*
Y-688978D01*
X441093Y-689019D01*
G01X443613Y-688936D02*
Y-686436D01*
X442626Y-688228D01*
X443960D01*
G01X444826Y-688936D02*
X445493Y-686436D01*
X446160Y-688936D01*
G01X445920Y-688061D02*
X445066D01*
G01X408593Y-661936D02*
Y-666936D01*
G01X407136Y-661936D02*
X410050D01*
G01X413693Y-666936D02*
X413313Y-666853D01*
X412933Y-666519D01*
X412680Y-665936D01*
X412553Y-665269D01*
X412680Y-664603D01*
X412933Y-664019D01*
X413313Y-663686D01*
X413693Y-663603D01*
X414073Y-663686D01*
X414453Y-664019D01*
X414706Y-664603D01*
X414770Y-665269D01*
X414706Y-665936D01*
X414453Y-666519D01*
X414073Y-666853D01*
X413693Y-666936D01*
G01X418793D02*
X418413Y-666853D01*
X418033Y-666519D01*
X417780Y-665936D01*
X417653Y-665269D01*
X417780Y-664603D01*
X418033Y-664019D01*
X418413Y-663686D01*
X418793Y-663603D01*
X419173Y-663686D01*
X419553Y-664019D01*
X419806Y-664603D01*
X419870Y-665269D01*
X419806Y-665936D01*
X419553Y-666519D01*
X419173Y-666853D01*
X418793Y-666936D01*
G01X423893D02*
Y-661936D01*
G01X428993Y-667103D02*
X428866Y-667019D01*
Y-666853D01*
X428993Y-666769D01*
X429120Y-666853D01*
Y-667019D01*
X428993Y-667103D01*
G01Y-664853D02*
X428866Y-664769D01*
Y-664603D01*
X428993Y-664519D01*
X429120Y-664603D01*
Y-664769D01*
X428993Y-664853D01*
G01X407326Y-641936D02*
Y-636936D01*
X408910D01*
X409416Y-637186D01*
X409733Y-637519D01*
X409860Y-638186D01*
X409733Y-638853D01*
X409353Y-639269D01*
X408910Y-639519D01*
X407326D01*
G01X408910D02*
X409860Y-641936D01*
G01X414960D02*
X412426D01*
Y-636936D01*
X414960D01*
G01X413946Y-639353D02*
X412426D01*
G01X417210Y-636936D02*
X418793Y-641936D01*
X420376Y-636936D01*
G01X423893Y-642103D02*
X423766Y-642019D01*
Y-641853D01*
X423893Y-641769D01*
X424020Y-641853D01*
Y-642019D01*
X423893Y-642103D01*
G01Y-639853D02*
X423766Y-639769D01*
Y-639603D01*
X423893Y-639519D01*
X424020Y-639603D01*
Y-639769D01*
X423893Y-639853D01*
G01X2010999Y-388000D02*
Y1475775D01*
X-407000D01*
Y-386798D01*
Y-755294D01*
Y-793716D01*
X-368578D01*
X1942346D01*
X2010999D01*
Y-725063D01*
Y-388000D01*
G01X-42602Y-671096D02*
X-41975Y-671621D01*
X-41270Y-671936D01*
X-40644D01*
X-40017Y-671621D01*
X-39547Y-671096D01*
X-39312Y-670361D01*
X-39469Y-669626D01*
X-39860Y-668996D01*
X-40565Y-668576D01*
X-41505Y-668366D01*
X-42054Y-667946D01*
X-42289Y-667211D01*
X-42132Y-666476D01*
X-41740Y-665951D01*
X-41192Y-665636D01*
X-40644D01*
X-40095Y-665846D01*
X-39625Y-666371D01*
G01X-36302Y-671936D02*
Y-665636D01*
G01X-33012D02*
Y-671936D01*
G01Y-668786D02*
X-36302D01*
G01X-29297Y-665636D02*
X-27417D01*
G01X-28357D02*
Y-671936D01*
G01X-29297D02*
X-27417D01*
G01X-20490D02*
X-23624D01*
Y-665636D01*
X-20490D01*
G01X-21744Y-668681D02*
X-23624D01*
G01X-17559Y-671936D02*
Y-665636D01*
X-13955Y-671936D01*
Y-665636D01*
G01X-9614Y-673091D02*
X-9300Y-671726D01*
G01X-3157Y-665636D02*
Y-671936D01*
G01X-4959Y-665636D02*
X-1355D01*
G01X1185Y-671936D02*
X3143Y-665636D01*
X5101Y-671936D01*
G01X4396Y-669731D02*
X1890D01*
G01X8503Y-665636D02*
X10383D01*
G01X9443D02*
Y-671936D01*
G01X8503D02*
X10383D01*
G01X13393Y-665636D02*
X14490Y-671936D01*
X15743Y-665636D01*
X16996Y-671936D01*
X18093Y-665636D01*
G01X20085Y-671936D02*
X22043Y-665636D01*
X24001Y-671936D01*
G01X23296Y-669731D02*
X20790D01*
G01X26541Y-671936D02*
Y-665636D01*
X30145Y-671936D01*
Y-665636D01*
G01X39376Y-671936D02*
Y-665636D01*
X41335D01*
X41961Y-665951D01*
X42353Y-666371D01*
X42510Y-667211D01*
X42353Y-668051D01*
X41883Y-668576D01*
X41335Y-668891D01*
X39376D01*
G01X41335D02*
X42510Y-671936D01*
G01X47243Y-672146D02*
X47086Y-672041D01*
Y-671831D01*
X47243Y-671726D01*
X47400Y-671831D01*
Y-672041D01*
X47243Y-672146D01*
G01X53543Y-671936D02*
X52916Y-671831D01*
X52368Y-671411D01*
X51898Y-670781D01*
X51585Y-670046D01*
X51428Y-669206D01*
Y-668366D01*
X51585Y-667526D01*
X51898Y-666791D01*
X52368Y-666161D01*
X52916Y-665741D01*
X53543Y-665636D01*
X54170Y-665741D01*
X54718Y-666161D01*
X55188Y-666791D01*
X55501Y-667526D01*
X55658Y-668366D01*
Y-669206D01*
X55501Y-670046D01*
X55188Y-670781D01*
X54718Y-671411D01*
X54170Y-671831D01*
X53543Y-671936D01*
G01X59843Y-672146D02*
X59686Y-672041D01*
Y-671831D01*
X59843Y-671726D01*
X60000Y-671831D01*
Y-672041D01*
X59843Y-672146D01*
G01X67866Y-666161D02*
X67396Y-665846D01*
X66848Y-665636D01*
X66221D01*
X65516Y-665951D01*
X64968Y-666476D01*
X64576Y-667106D01*
X64263Y-668156D01*
X64185Y-669101D01*
X64341Y-670046D01*
X64576Y-670676D01*
X65046Y-671306D01*
X65595Y-671726D01*
X66143Y-671936D01*
X66691D01*
X67240Y-671726D01*
X67710Y-671411D01*
X68101Y-670991D01*
G01X72443Y-672146D02*
X72286Y-672041D01*
Y-671831D01*
X72443Y-671726D01*
X72600Y-671831D01*
Y-672041D01*
X72443Y-672146D01*
G01X-42680Y-661936D02*
Y-655636D01*
G01X-39704D02*
X-42680Y-659521D01*
G01X-39234Y-661936D02*
X-41349Y-657736D01*
G01X-36380Y-655636D02*
Y-660151D01*
X-36067Y-661096D01*
X-35440Y-661726D01*
X-34657Y-661936D01*
X-33874Y-661726D01*
X-33247Y-661096D01*
X-32934Y-660151D01*
Y-655636D01*
G01X-26790Y-661936D02*
X-29924D01*
Y-655636D01*
X-26790D01*
G01X-28044Y-658681D02*
X-29924D01*
G01X-22997Y-655636D02*
X-21117D01*
G01X-22057D02*
Y-661936D01*
G01X-22997D02*
X-21117D01*
G01X-11102Y-661096D02*
X-10475Y-661621D01*
X-9770Y-661936D01*
X-9144D01*
X-8517Y-661621D01*
X-8047Y-661096D01*
X-7812Y-660361D01*
X-7969Y-659626D01*
X-8360Y-658996D01*
X-9065Y-658576D01*
X-10005Y-658366D01*
X-10554Y-657946D01*
X-10789Y-657211D01*
X-10632Y-656476D01*
X-10240Y-655951D01*
X-9692Y-655636D01*
X-9144D01*
X-8595Y-655846D01*
X-8125Y-656371D01*
G01X-4802Y-661936D02*
Y-655636D01*
G01X-1512D02*
Y-661936D01*
G01Y-658786D02*
X-4802D01*
G01X1185Y-661936D02*
X3143Y-655636D01*
X5101Y-661936D01*
G01X4396Y-659731D02*
X1890D01*
G01X7641Y-661936D02*
Y-655636D01*
X11245Y-661936D01*
Y-655636D01*
G01X20398Y-661936D02*
Y-655636D01*
G01X23688D02*
Y-661936D01*
G01Y-658786D02*
X20398D01*
G01X26698Y-661096D02*
X27325Y-661621D01*
X28030Y-661936D01*
X28656D01*
X29283Y-661621D01*
X29753Y-661096D01*
X29988Y-660361D01*
X29831Y-659626D01*
X29440Y-658996D01*
X28735Y-658576D01*
X27795Y-658366D01*
X27246Y-657946D01*
X27011Y-657211D01*
X27168Y-656476D01*
X27560Y-655951D01*
X28108Y-655636D01*
X28656D01*
X29205Y-655846D01*
X29675Y-656371D01*
G01X33703Y-655636D02*
X35583D01*
G01X34643D02*
Y-661936D01*
G01X33703D02*
X35583D01*
G01X38985D02*
X40943Y-655636D01*
X42901Y-661936D01*
G01X42196Y-659731D02*
X39690D01*
G01X45441Y-661936D02*
Y-655636D01*
X49045Y-661936D01*
Y-655636D01*
G01X54013Y-658786D02*
X55580D01*
Y-660676D01*
X55110Y-661306D01*
X54561Y-661726D01*
X53778Y-661936D01*
X52995Y-661726D01*
X52446Y-661306D01*
X51976Y-660676D01*
X51663Y-659941D01*
X51506Y-659101D01*
Y-658366D01*
X51663Y-657736D01*
X51976Y-657001D01*
X52446Y-656371D01*
X52916Y-655951D01*
X53543Y-655636D01*
X54091D01*
X54718Y-655846D01*
X55188Y-656266D01*
G01X59686Y-663091D02*
X60000Y-661726D01*
G01X66143Y-655636D02*
Y-661936D01*
G01X64341Y-655636D02*
X67945D01*
G01X70485Y-661936D02*
X72443Y-655636D01*
X74401Y-661936D01*
G01X73696Y-659731D02*
X71190D01*
G01X78743Y-661936D02*
X78116Y-661831D01*
X77568Y-661411D01*
X77098Y-660781D01*
X76785Y-660046D01*
X76628Y-659206D01*
Y-658366D01*
X76785Y-657526D01*
X77098Y-656791D01*
X77568Y-656161D01*
X78116Y-655741D01*
X78743Y-655636D01*
X79370Y-655741D01*
X79918Y-656161D01*
X80388Y-656791D01*
X80701Y-657526D01*
X80858Y-658366D01*
Y-659206D01*
X80701Y-660046D01*
X80388Y-660781D01*
X79918Y-661411D01*
X79370Y-661831D01*
X78743Y-661936D01*
G01X91343D02*
Y-659101D01*
X89776Y-655636D01*
G01X92910D02*
X91343Y-659101D01*
G01X95920Y-655636D02*
Y-660151D01*
X96233Y-661096D01*
X96860Y-661726D01*
X97643Y-661936D01*
X98426Y-661726D01*
X99053Y-661096D01*
X99366Y-660151D01*
Y-655636D01*
G01X101985Y-661936D02*
X103943Y-655636D01*
X105901Y-661936D01*
G01X105196Y-659731D02*
X102690D01*
G01X108441Y-661936D02*
Y-655636D01*
X112045Y-661936D01*
Y-655636D01*
G01X-42759Y-651936D02*
Y-645636D01*
X-39155Y-651936D01*
Y-645636D01*
G01X-34657Y-651936D02*
X-35284Y-651831D01*
X-35832Y-651411D01*
X-36302Y-650781D01*
X-36615Y-650046D01*
X-36772Y-649206D01*
Y-648366D01*
X-36615Y-647526D01*
X-36302Y-646791D01*
X-35832Y-646161D01*
X-35284Y-645741D01*
X-34657Y-645636D01*
X-34030Y-645741D01*
X-33482Y-646161D01*
X-33012Y-646791D01*
X-32699Y-647526D01*
X-32542Y-648366D01*
Y-649206D01*
X-32699Y-650046D01*
X-33012Y-650781D01*
X-33482Y-651411D01*
X-34030Y-651831D01*
X-34657Y-651936D01*
G01X-28357Y-652146D02*
X-28514Y-652041D01*
Y-651831D01*
X-28357Y-651726D01*
X-28200Y-651831D01*
Y-652041D01*
X-28357Y-652146D01*
G01X-22057Y-651936D02*
Y-645636D01*
X-22997Y-646896D01*
G01Y-651936D02*
X-21117D01*
G01X-15757D02*
X-15209Y-651831D01*
X-14582Y-651516D01*
X-14190Y-650991D01*
X-14034Y-650256D01*
X-14190Y-649521D01*
X-14660Y-648891D01*
X-15365Y-648576D01*
X-16149D01*
X-16619Y-648366D01*
X-17010Y-647841D01*
X-17167Y-647106D01*
X-16932Y-646371D01*
X-16384Y-645846D01*
X-15757Y-645636D01*
X-15130Y-645846D01*
X-14582Y-646371D01*
X-14347Y-647106D01*
X-14504Y-647841D01*
X-14895Y-648366D01*
X-15365Y-648576D01*
X-16149D01*
X-16854Y-648891D01*
X-17324Y-649521D01*
X-17480Y-650256D01*
X-17324Y-650991D01*
X-16932Y-651516D01*
X-16305Y-651831D01*
X-15757Y-651936D01*
G01X-9457D02*
X-8909Y-651831D01*
X-8282Y-651516D01*
X-7890Y-650991D01*
X-7734Y-650256D01*
X-7890Y-649521D01*
X-8360Y-648891D01*
X-9065Y-648576D01*
X-9849D01*
X-10319Y-648366D01*
X-10710Y-647841D01*
X-10867Y-647106D01*
X-10632Y-646371D01*
X-10084Y-645846D01*
X-9457Y-645636D01*
X-8830Y-645846D01*
X-8282Y-646371D01*
X-8047Y-647106D01*
X-8204Y-647841D01*
X-8595Y-648366D01*
X-9065Y-648576D01*
X-9849D01*
X-10554Y-648891D01*
X-11024Y-649521D01*
X-11180Y-650256D01*
X-11024Y-650991D01*
X-10632Y-651516D01*
X-10005Y-651831D01*
X-9457Y-651936D01*
G01X-3314Y-653091D02*
X-3000Y-651726D01*
G01X793Y-645636D02*
X1890Y-651936D01*
X3143Y-645636D01*
X4396Y-651936D01*
X5493Y-645636D01*
G01X11010Y-651936D02*
X7876D01*
Y-645636D01*
X11010D01*
G01X9756Y-648681D02*
X7876D01*
G01X13941Y-651936D02*
Y-645636D01*
X17545Y-651936D01*
Y-645636D01*
G01X26698Y-651936D02*
Y-645636D01*
G01X29988D02*
Y-651936D01*
G01Y-648786D02*
X26698D01*
G01X32293Y-645636D02*
X33390Y-651936D01*
X34643Y-645636D01*
X35896Y-651936D01*
X36993Y-645636D01*
G01X38985Y-651936D02*
X40943Y-645636D01*
X42901Y-651936D01*
G01X42196Y-649731D02*
X39690D01*
G01X52055Y-646686D02*
X52525Y-646056D01*
X53073Y-645741D01*
X53700Y-645636D01*
X54483Y-645846D01*
X55031Y-646371D01*
X55188Y-647001D01*
X55110Y-647631D01*
X54796Y-648156D01*
X53230Y-649206D01*
X52525Y-649941D01*
X52055Y-650991D01*
X51898Y-651936D01*
X55188D01*
G01X58041D02*
Y-645636D01*
X61645Y-651936D01*
Y-645636D01*
G01X64420Y-651936D02*
Y-645636D01*
X65986D01*
X66613Y-645951D01*
X67083Y-646371D01*
X67475Y-647001D01*
X67788Y-647736D01*
X67866Y-648786D01*
X67788Y-649836D01*
X67475Y-650571D01*
X67083Y-651201D01*
X66613Y-651621D01*
X65986Y-651936D01*
X64420D01*
G01X77176D02*
Y-645636D01*
X79135D01*
X79761Y-645951D01*
X80153Y-646371D01*
X80310Y-647211D01*
X80153Y-648051D01*
X79683Y-648576D01*
X79135Y-648891D01*
X77176D01*
G01X79135D02*
X80310Y-651936D01*
G01X83320D02*
Y-645636D01*
X84886D01*
X85513Y-645951D01*
X85983Y-646371D01*
X86375Y-647001D01*
X86688Y-647736D01*
X86766Y-648786D01*
X86688Y-649836D01*
X86375Y-650571D01*
X85983Y-651201D01*
X85513Y-651621D01*
X84886Y-651936D01*
X83320D01*
G01X91343Y-652146D02*
X91186Y-652041D01*
Y-651831D01*
X91343Y-651726D01*
X91500Y-651831D01*
Y-652041D01*
X91343Y-652146D01*
G01X-18657Y-639236D02*
X-21177Y-638819D01*
X-23382Y-637153D01*
X-25272Y-634653D01*
X-26532Y-631736D01*
X-27162Y-628403D01*
Y-625069D01*
X-26532Y-621736D01*
X-25272Y-618819D01*
X-23382Y-616320D01*
X-21177Y-614653D01*
X-18657Y-614236D01*
X-16137Y-614653D01*
X-13932Y-616320D01*
X-12042Y-618819D01*
X-10782Y-621736D01*
X-10152Y-625069D01*
Y-628403D01*
X-10782Y-631736D01*
X-12042Y-634653D01*
X-13932Y-637153D01*
X-16137Y-638819D01*
X-18657Y-639236D01*
G01X-16137Y-632569D02*
X-12357Y-639236D01*
G01X1188Y-622570D02*
Y-634236D01*
X2448Y-637153D01*
X4338Y-638819D01*
X6543Y-639236D01*
X8748Y-638819D01*
X10638Y-637153D01*
X11898Y-634236D01*
G01Y-639236D02*
Y-622570D01*
G01X37413Y-639236D02*
Y-622570D01*
G01Y-625486D02*
X36153Y-623820D01*
X34263Y-622986D01*
X32058Y-622570D01*
X29853Y-623403D01*
X27963Y-625069D01*
X26703Y-627570D01*
X26073Y-630903D01*
X26703Y-634236D01*
X27963Y-636737D01*
X29853Y-638403D01*
X32058Y-639236D01*
X34263Y-638819D01*
X36153Y-637570D01*
X37413Y-635903D01*
G01X51588Y-639236D02*
Y-622570D01*
G01Y-626736D02*
X52848Y-624653D01*
X54738Y-622986D01*
X57258Y-622570D01*
X59463Y-622986D01*
X61353Y-624653D01*
X62298Y-627570D01*
Y-639236D01*
G01X82143Y-614236D02*
Y-639236D01*
G01X77733Y-622570D02*
X86553D01*
G01X113013Y-639236D02*
Y-622570D01*
G01Y-625486D02*
X111753Y-623820D01*
X109863Y-622986D01*
X107658Y-622570D01*
X105453Y-623403D01*
X103563Y-625069D01*
X102303Y-627570D01*
X101673Y-630903D01*
X102303Y-634236D01*
X103563Y-636737D01*
X105453Y-638403D01*
X107658Y-639236D01*
X109863Y-638819D01*
X111753Y-637570D01*
X113013Y-635903D01*
G01X152693Y-618936D02*
Y-626936D01*
X156693D01*
G01X164493D02*
Y-621603D01*
G01Y-622536D02*
X164093Y-622003D01*
X163493Y-621736D01*
X162793Y-621603D01*
X162093Y-621869D01*
X161493Y-622403D01*
X161093Y-623203D01*
X160893Y-624269D01*
X161093Y-625336D01*
X161493Y-626136D01*
X162093Y-626669D01*
X162793Y-626936D01*
X163493Y-626803D01*
X164093Y-626403D01*
X164493Y-625870D01*
G01X168593Y-629336D02*
X169193Y-629603D01*
X169993Y-629336D01*
X170493Y-628803D01*
X170893Y-628136D01*
X171493Y-626003D01*
X172793Y-621603D01*
G01X169593D02*
X171493Y-626003D01*
G01X177193Y-623336D02*
X180393D01*
X180093Y-622403D01*
X179593Y-621869D01*
X178893Y-621603D01*
X178193Y-621736D01*
X177593Y-622136D01*
X177193Y-623069D01*
X176993Y-623870D01*
Y-624669D01*
X177193Y-625469D01*
X177693Y-626269D01*
X178293Y-626803D01*
X178993Y-626936D01*
X179693Y-626669D01*
X180393Y-625870D01*
G01X185293Y-626936D02*
Y-621603D01*
G01Y-622669D02*
X185793Y-622136D01*
X186293Y-621736D01*
X186993Y-621603D01*
X187493Y-621736D01*
X188093Y-622136D01*
G01X173993Y-676936D02*
Y-668936D01*
G01X177793D02*
X173993Y-673870D01*
G01X178393Y-676936D02*
X175693Y-671603D01*
G01X185993Y-676936D02*
Y-671603D01*
G01Y-672536D02*
X185593Y-672003D01*
X184993Y-671736D01*
X184293Y-671603D01*
X183593Y-671869D01*
X182993Y-672403D01*
X182593Y-673203D01*
X182393Y-674269D01*
X182593Y-675336D01*
X182993Y-676136D01*
X183593Y-676669D01*
X184293Y-676936D01*
X184993Y-676803D01*
X185593Y-676403D01*
X185993Y-675870D01*
G01X192193Y-671603D02*
Y-676936D01*
G01Y-669469D02*
X191993Y-669336D01*
Y-669069D01*
X192193Y-668936D01*
X192393Y-669069D01*
Y-669336D01*
X192193Y-669469D01*
G01X184993Y-643936D02*
X187393D01*
G01X186193D02*
Y-651936D01*
G01X184993D02*
X187393D01*
G01X191893D02*
Y-643936D01*
X196493Y-651936D01*
Y-643936D01*
G01X203393Y-651936D02*
Y-643936D01*
X199693Y-649669D01*
X204693D01*
G01X206193Y-626936D02*
Y-618936D01*
X204993Y-620536D01*
G01Y-626936D02*
X207393D01*
G01X214193Y-618936D02*
X213393Y-619203D01*
X212793Y-619869D01*
X212393Y-620669D01*
X212093Y-621736D01*
X211993Y-622936D01*
X212093Y-624136D01*
X212393Y-625203D01*
X212793Y-626003D01*
X213393Y-626669D01*
X214193Y-626936D01*
X214993Y-626669D01*
X215593Y-626003D01*
X215993Y-625203D01*
X216293Y-624136D01*
X216393Y-622936D01*
X216293Y-621736D01*
X215993Y-620669D01*
X215593Y-619869D01*
X214993Y-619203D01*
X214193Y-618936D01*
G01X279293Y-670269D02*
X279893Y-669469D01*
X280593Y-669069D01*
X281393Y-668936D01*
X282393Y-669203D01*
X283093Y-669869D01*
X283293Y-670669D01*
X283193Y-671470D01*
X282793Y-672136D01*
X280793Y-673469D01*
X279893Y-674403D01*
X279293Y-675736D01*
X279093Y-676936D01*
X283293D01*
G01X289193Y-668936D02*
X288393Y-669203D01*
X287793Y-669869D01*
X287393Y-670669D01*
X287093Y-671736D01*
X286993Y-672936D01*
X287093Y-674136D01*
X287393Y-675203D01*
X287793Y-676003D01*
X288393Y-676669D01*
X289193Y-676936D01*
X289993Y-676669D01*
X290593Y-676003D01*
X290993Y-675203D01*
X291293Y-674136D01*
X291393Y-672936D01*
X291293Y-671736D01*
X290993Y-670669D01*
X290593Y-669869D01*
X289993Y-669203D01*
X289193Y-668936D01*
G01X295293Y-670269D02*
X295893Y-669469D01*
X296593Y-669069D01*
X297393Y-668936D01*
X298393Y-669203D01*
X299093Y-669869D01*
X299293Y-670669D01*
X299193Y-671470D01*
X298793Y-672136D01*
X296793Y-673469D01*
X295893Y-674403D01*
X295293Y-675736D01*
X295093Y-676936D01*
X299293D01*
G01X303293Y-670269D02*
X303893Y-669469D01*
X304593Y-669069D01*
X305393Y-668936D01*
X306393Y-669203D01*
X307093Y-669869D01*
X307293Y-670669D01*
X307193Y-671470D01*
X306793Y-672136D01*
X304793Y-673469D01*
X303893Y-674403D01*
X303293Y-675736D01*
X303093Y-676936D01*
X307293D01*
G01X311393Y-677203D02*
X314993Y-668936D01*
G01X321193Y-676936D02*
Y-668936D01*
X319993Y-670536D01*
G01Y-676936D02*
X322393D01*
G01X327293Y-670269D02*
X327893Y-669469D01*
X328593Y-669069D01*
X329393Y-668936D01*
X330393Y-669203D01*
X331093Y-669869D01*
X331293Y-670669D01*
X331193Y-671470D01*
X330793Y-672136D01*
X328793Y-673469D01*
X327893Y-674403D01*
X327293Y-675736D01*
X327093Y-676936D01*
X331293D01*
G01X335393Y-677203D02*
X338993Y-668936D01*
G01X345193D02*
X344393Y-669203D01*
X343793Y-669869D01*
X343393Y-670669D01*
X343093Y-671736D01*
X342993Y-672936D01*
X343093Y-674136D01*
X343393Y-675203D01*
X343793Y-676003D01*
X344393Y-676669D01*
X345193Y-676936D01*
X345993Y-676669D01*
X346593Y-676003D01*
X346993Y-675203D01*
X347293Y-674136D01*
X347393Y-672936D01*
X347293Y-671736D01*
X346993Y-670669D01*
X346593Y-669869D01*
X345993Y-669203D01*
X345193Y-668936D01*
G01X351493Y-676003D02*
X352193Y-676669D01*
X352993Y-676936D01*
X353793Y-676669D01*
X354493Y-675870D01*
X354993Y-674669D01*
X355193Y-673469D01*
Y-672003D01*
X354993Y-670803D01*
X354493Y-669736D01*
X353893Y-669203D01*
X353193Y-668936D01*
X352393Y-669203D01*
X351793Y-669736D01*
X351393Y-670536D01*
X351193Y-671603D01*
X351393Y-672536D01*
X351893Y-673469D01*
X352493Y-674003D01*
X353193Y-674136D01*
X353993Y-673870D01*
X354593Y-673203D01*
X355193Y-672003D01*
G01X278993Y-651936D02*
Y-643936D01*
X280993D01*
X281793Y-644336D01*
X282393Y-644869D01*
X282893Y-645669D01*
X283293Y-646603D01*
X283393Y-647936D01*
X283293Y-649269D01*
X282893Y-650203D01*
X282393Y-651003D01*
X281793Y-651536D01*
X280993Y-651936D01*
X278993D01*
G01X286693D02*
X289193Y-643936D01*
X291693Y-651936D01*
G01X290793Y-649136D02*
X287593D01*
G01X297193Y-643936D02*
X296393Y-644203D01*
X295793Y-644869D01*
X295393Y-645669D01*
X295093Y-646736D01*
X294993Y-647936D01*
X295093Y-649136D01*
X295393Y-650203D01*
X295793Y-651003D01*
X296393Y-651669D01*
X297193Y-651936D01*
X297993Y-651669D01*
X298593Y-651003D01*
X298993Y-650203D01*
X299293Y-649136D01*
X299393Y-647936D01*
X299293Y-646736D01*
X298993Y-645669D01*
X298593Y-644869D01*
X297993Y-644203D01*
X297193Y-643936D01*
G01X303293Y-651936D02*
Y-643936D01*
X307093D01*
G01X305693Y-647803D02*
X303293D01*
G01X313193Y-643936D02*
X312393Y-644203D01*
X311793Y-644869D01*
X311393Y-645669D01*
X311093Y-646736D01*
X310993Y-647936D01*
X311093Y-649136D01*
X311393Y-650203D01*
X311793Y-651003D01*
X312393Y-651669D01*
X313193Y-651936D01*
X313993Y-651669D01*
X314593Y-651003D01*
X314993Y-650203D01*
X315293Y-649136D01*
X315393Y-647936D01*
X315293Y-646736D01*
X314993Y-645669D01*
X314593Y-644869D01*
X313993Y-644203D01*
X313193Y-643936D01*
G01X321193D02*
Y-651936D01*
G01X318893Y-643936D02*
X323493D01*
G01X326593Y-651936D02*
Y-643936D01*
X329193Y-650603D01*
X331793Y-643936D01*
Y-651936D01*
G01X334993D02*
Y-643936D01*
X336993D01*
X337793Y-644336D01*
X338393Y-644869D01*
X338893Y-645669D01*
X339293Y-646603D01*
X339393Y-647936D01*
X339293Y-649269D01*
X338893Y-650203D01*
X338393Y-651003D01*
X337793Y-651536D01*
X336993Y-651936D01*
X334993D01*
G01X347393Y-644603D02*
X346793Y-644203D01*
X346093Y-643936D01*
X345293D01*
X344393Y-644336D01*
X343693Y-645003D01*
X343193Y-645803D01*
X342793Y-647136D01*
X342693Y-648336D01*
X342893Y-649536D01*
X343193Y-650336D01*
X343793Y-651136D01*
X344493Y-651669D01*
X345193Y-651936D01*
X345893D01*
X346593Y-651669D01*
X347193Y-651269D01*
X347693Y-650736D01*
G01X350993Y-651936D02*
Y-643936D01*
X352993D01*
X353793Y-644336D01*
X354393Y-644869D01*
X354893Y-645669D01*
X355293Y-646603D01*
X355393Y-647936D01*
X355293Y-649269D01*
X354893Y-650203D01*
X354393Y-651003D01*
X353793Y-651536D01*
X352993Y-651936D01*
X350993D01*
G01X361193Y-643936D02*
X360393Y-644203D01*
X359793Y-644869D01*
X359393Y-645669D01*
X359093Y-646736D01*
X358993Y-647936D01*
X359093Y-649136D01*
X359393Y-650203D01*
X359793Y-651003D01*
X360393Y-651669D01*
X361193Y-651936D01*
X361993Y-651669D01*
X362593Y-651003D01*
X362993Y-650203D01*
X363293Y-649136D01*
X363393Y-647936D01*
X363293Y-646736D01*
X362993Y-645669D01*
X362593Y-644869D01*
X361993Y-644203D01*
X361193Y-643936D01*
G01X298418Y-624819D02*
Y-618519D01*
X301394D01*
G01X300298Y-621564D02*
X298418D01*
G01X306206Y-618519D02*
X305579Y-618729D01*
X305109Y-619254D01*
X304796Y-619884D01*
X304561Y-620724D01*
X304483Y-621669D01*
X304561Y-622614D01*
X304796Y-623454D01*
X305109Y-624084D01*
X305579Y-624609D01*
X306206Y-624819D01*
X306833Y-624609D01*
X307303Y-624084D01*
X307616Y-623454D01*
X307851Y-622614D01*
X307929Y-621669D01*
X307851Y-620724D01*
X307616Y-619884D01*
X307303Y-619254D01*
X306833Y-618729D01*
X306206Y-618519D01*
G01X312506D02*
Y-624819D01*
G01X310704Y-618519D02*
X314308D01*
G01X316456Y-626919D02*
X321156D01*
G01X323069Y-624819D02*
Y-618519D01*
X325106Y-623769D01*
X327143Y-618519D01*
Y-624819D01*
G01X332816D02*
Y-620619D01*
G01Y-621354D02*
X332503Y-620934D01*
X332033Y-620724D01*
X331484Y-620619D01*
X330936Y-620829D01*
X330466Y-621249D01*
X330153Y-621879D01*
X329996Y-622719D01*
X330153Y-623559D01*
X330466Y-624189D01*
X330936Y-624609D01*
X331484Y-624819D01*
X332033Y-624714D01*
X332503Y-624399D01*
X332816Y-623979D01*
G01X336374Y-624819D02*
Y-620619D01*
G01Y-621669D02*
X336688Y-621144D01*
X337158Y-620724D01*
X337784Y-620619D01*
X338333Y-620724D01*
X338803Y-621144D01*
X339038Y-621879D01*
Y-624819D01*
G01X345416D02*
Y-620619D01*
G01Y-621354D02*
X345103Y-620934D01*
X344633Y-620724D01*
X344084Y-620619D01*
X343536Y-620829D01*
X343066Y-621249D01*
X342753Y-621879D01*
X342596Y-622719D01*
X342753Y-623559D01*
X343066Y-624189D01*
X343536Y-624609D01*
X344084Y-624819D01*
X344633Y-624714D01*
X345103Y-624399D01*
X345416Y-623979D01*
G01X349209Y-626394D02*
X349758Y-626814D01*
X350384Y-626919D01*
X350933Y-626814D01*
X351403Y-626289D01*
X351716Y-625554D01*
Y-620619D01*
G01Y-621459D02*
X351403Y-621039D01*
X350933Y-620724D01*
X350384Y-620619D01*
X349758Y-620829D01*
X349366Y-621249D01*
X349053Y-621984D01*
X348896Y-622719D01*
X348974Y-623349D01*
X349288Y-624084D01*
X349758Y-624609D01*
X350384Y-624819D01*
X350854Y-624714D01*
X351403Y-624294D01*
X351716Y-623874D01*
G01X355431Y-621984D02*
X357938D01*
X357703Y-621249D01*
X357311Y-620829D01*
X356763Y-620619D01*
X356214Y-620724D01*
X355744Y-621039D01*
X355431Y-621774D01*
X355274Y-622404D01*
Y-623034D01*
X355431Y-623664D01*
X355823Y-624294D01*
X356293Y-624714D01*
X356841Y-624819D01*
X357389Y-624609D01*
X357938Y-623979D01*
G01X360556Y-624819D02*
Y-620619D01*
G01Y-621774D02*
X360791Y-621249D01*
X361183Y-620829D01*
X361731Y-620619D01*
X362279Y-620829D01*
X362671Y-621249D01*
X362906Y-621774D01*
Y-624819D01*
G01Y-621774D02*
X363141Y-621249D01*
X363533Y-620829D01*
X364081Y-620619D01*
X364629Y-620829D01*
X365021Y-621249D01*
X365256Y-621879D01*
Y-624819D01*
G01X368031Y-621984D02*
X370538D01*
X370303Y-621249D01*
X369911Y-620829D01*
X369363Y-620619D01*
X368814Y-620724D01*
X368344Y-621039D01*
X368031Y-621774D01*
X367874Y-622404D01*
Y-623034D01*
X368031Y-623664D01*
X368423Y-624294D01*
X368893Y-624714D01*
X369441Y-624819D01*
X369989Y-624609D01*
X370538Y-623979D01*
G01X374174Y-624819D02*
Y-620619D01*
G01Y-621669D02*
X374488Y-621144D01*
X374958Y-620724D01*
X375584Y-620619D01*
X376133Y-620724D01*
X376603Y-621144D01*
X376838Y-621879D01*
Y-624819D01*
G01X381806Y-618519D02*
Y-624819D01*
G01X380709Y-620619D02*
X382903D01*
G01X385756Y-626919D02*
X390456D01*
G01X395033Y-621459D02*
X395346Y-621144D01*
X395581Y-620619D01*
X395738Y-619884D01*
X395581Y-619254D01*
X395268Y-618834D01*
X394719Y-618519D01*
X392604D01*
Y-624819D01*
X395189D01*
X395738Y-624399D01*
X396051Y-623769D01*
X396208Y-623034D01*
X396051Y-622299D01*
X395581Y-621669D01*
X395033Y-621459D01*
X392604D01*
G01X398983Y-624819D02*
Y-618519D01*
X400549D01*
X401176Y-618834D01*
X401646Y-619254D01*
X402038Y-619884D01*
X402351Y-620619D01*
X402429Y-621669D01*
X402351Y-622719D01*
X402038Y-623454D01*
X401646Y-624084D01*
X401176Y-624504D01*
X400549Y-624819D01*
X398983D01*
G01X367693Y-679936D02*
Y-671936D01*
X366493Y-673536D01*
G01Y-679936D02*
X368893D01*
G01X373793Y-676603D02*
X374493Y-675669D01*
X375093Y-675136D01*
X375893Y-674869D01*
X376593Y-675136D01*
X377093Y-675669D01*
X377493Y-676469D01*
X377593Y-677403D01*
X377493Y-678203D01*
X377093Y-679003D01*
X376493Y-679669D01*
X375793Y-679936D01*
X374993Y-679669D01*
X374293Y-678870D01*
X373893Y-677669D01*
X373793Y-676336D01*
X373993Y-674603D01*
X374293Y-673669D01*
X374793Y-672736D01*
X375493Y-672069D01*
X376193Y-671936D01*
X376893Y-672203D01*
X377393Y-672869D01*
G01X383693Y-680203D02*
X383493Y-680069D01*
Y-679803D01*
X383693Y-679669D01*
X383893Y-679803D01*
Y-680069D01*
X383693Y-680203D01*
G01X389793Y-676603D02*
X390493Y-675669D01*
X391093Y-675136D01*
X391893Y-674869D01*
X392593Y-675136D01*
X393093Y-675669D01*
X393493Y-676469D01*
X393593Y-677403D01*
X393493Y-678203D01*
X393093Y-679003D01*
X392493Y-679669D01*
X391793Y-679936D01*
X390993Y-679669D01*
X390293Y-678870D01*
X389893Y-677669D01*
X389793Y-676336D01*
X389993Y-674603D01*
X390293Y-673669D01*
X390793Y-672736D01*
X391493Y-672069D01*
X392193Y-671936D01*
X392893Y-672203D01*
X393393Y-672869D01*
G01X412693Y-679936D02*
Y-671936D01*
X411493Y-673536D01*
G01Y-679936D02*
X413893D01*
G01X420493D02*
X420693Y-678203D01*
X420993Y-676736D01*
X421393Y-675403D01*
X421893Y-673936D01*
X422693Y-671936D01*
X418693D01*
G01X428693Y-680203D02*
X428493Y-680069D01*
Y-679803D01*
X428693Y-679669D01*
X428893Y-679803D01*
Y-680069D01*
X428693Y-680203D01*
G01X434793Y-673269D02*
X435393Y-672469D01*
X436093Y-672069D01*
X436893Y-671936D01*
X437893Y-672203D01*
X438593Y-672869D01*
X438793Y-673669D01*
X438693Y-674470D01*
X438293Y-675136D01*
X436293Y-676469D01*
X435393Y-677403D01*
X434793Y-678736D01*
X434593Y-679936D01*
X438793D01*
G01X432493Y-654936D02*
Y-646936D01*
X434493D01*
X435293Y-647336D01*
X435893Y-647869D01*
X436393Y-648669D01*
X436793Y-649603D01*
X436893Y-650936D01*
X436793Y-652269D01*
X436393Y-653203D01*
X435893Y-654003D01*
X435293Y-654536D01*
X434493Y-654936D01*
X432493D01*
G54D17*
G01X-61709Y56192D02*
Y67512D01*
X-62209Y68012D01*
X-64489D01*
X-67582Y71105D01*
Y75639D01*
X-64489Y78732D01*
X-50742D01*
X-49722Y79752D01*
Y81352D01*
X-50742Y82372D01*
X-64489D01*
X-67582Y85465D01*
Y89999D01*
X-64489Y93092D01*
X-50742D01*
X-49722Y94112D01*
Y95712D01*
X-50742Y96732D01*
X-64489D01*
X-67582Y99825D01*
Y104359D01*
X-64489Y107452D01*
X-50742D01*
X-49722Y108472D01*
Y110072D01*
X-50742Y111092D01*
X-64489D01*
X-67582Y114185D01*
Y118719D01*
X-64489Y121812D01*
X-50742D01*
X-49722Y122832D01*
Y124432D01*
X-50742Y125452D01*
X-64489D01*
X-67582Y128545D01*
Y133079D01*
X-64489Y136172D01*
X-50742D01*
X-49722Y137192D01*
Y138792D01*
X-50742Y139812D01*
X-64489D01*
X-67582Y142905D01*
Y147439D01*
X-64489Y150532D01*
X-50742D01*
X-49722Y151552D01*
Y153152D01*
X-50742Y154172D01*
X-64489D01*
X-67582Y157265D01*
Y161050D01*
X-66580Y162052D01*
X-65080D01*
X-64042Y161014D01*
Y158732D01*
X-63022Y157712D01*
X-49275D01*
X-46182Y154619D01*
Y150085D01*
X-49275Y146992D01*
X-63022D01*
X-64042Y145972D01*
Y144372D01*
X-63022Y143352D01*
X-49275D01*
X-46182Y140259D01*
Y135725D01*
X-49275Y132632D01*
X-63022D01*
X-64042Y131612D01*
Y130012D01*
X-63022Y128992D01*
X-49275D01*
X-46182Y125899D01*
Y121365D01*
X-49275Y118272D01*
X-63022D01*
X-64042Y117252D01*
Y115652D01*
X-63022Y114632D01*
X-49275D01*
X-46182Y111539D01*
Y107005D01*
X-49275Y103912D01*
X-63022D01*
X-64042Y102892D01*
Y101292D01*
X-63022Y100272D01*
X-49275D01*
X-46182Y97179D01*
Y92645D01*
X-49275Y89552D01*
X-63022D01*
X-64042Y88532D01*
Y86932D01*
X-63022Y85912D01*
X-49275D01*
X-46182Y82819D01*
Y78285D01*
X-49275Y75192D01*
X-63022D01*
X-64042Y74172D01*
Y72572D01*
X-63022Y71552D01*
X-52209D01*
X-51709Y71052D01*
Y56192D01*
G01X13869Y352239D02*
X16789Y355159D01*
Y413196D01*
X23677Y420084D01*
Y422419D01*
G01X14600Y422500D02*
X15872D01*
X18564Y425192D01*
X21650D01*
X24283Y427825D01*
X26848D01*
X33190Y421483D01*
Y419250D01*
X41940Y410500D01*
Y406376D01*
X46320Y401996D01*
Y395504D01*
X48840Y392984D01*
Y388416D01*
X46424Y386000D01*
X42801D01*
X42200Y385399D01*
Y380200D01*
X40000Y378000D01*
Y349828D01*
X43628Y346200D01*
X44800D01*
X46400Y344600D01*
Y335800D01*
X50720Y331480D01*
Y321219D01*
X52715Y319224D01*
Y317386D01*
X56425Y313676D01*
Y310153D01*
X53685Y307413D01*
Y250705D01*
X61200Y243190D01*
Y237100D01*
X62300Y236000D01*
Y234236D01*
X61060Y232996D01*
Y225662D01*
X61915Y224807D01*
Y191670D01*
X61076Y190831D01*
Y186010D01*
X64761Y182325D01*
Y169338D01*
X69184Y164915D01*
X77615D01*
X78400Y165700D01*
X83165D01*
X89865Y159000D01*
Y142235D01*
X89170Y141540D01*
G01X35500Y340500D02*
X31300Y344700D01*
X29700D01*
X28200Y343200D01*
X22000D01*
X18500Y346700D01*
Y411000D01*
X20870Y413370D01*
X35260D01*
X39530Y409100D01*
G01X44525Y394150D02*
X44325Y394350D01*
X43551D01*
X34401Y403500D01*
X21300D01*
X19730Y401930D01*
Y347210D01*
X22510Y344430D01*
X26963D01*
X28998Y346465D01*
X32469D01*
X38145Y340789D01*
Y333561D01*
X35500Y330916D01*
Y319801D01*
X37637Y317664D01*
X38635D01*
X43812Y312489D01*
X43852Y312447D01*
X44370Y311929D01*
Y299533D01*
X46160Y297743D01*
Y277230D01*
X46220Y277170D01*
G01X58000Y217700D02*
Y225242D01*
X56825Y226417D01*
Y241778D01*
X48928Y249675D01*
Y264663D01*
X52455Y268190D01*
Y313912D01*
X48325Y318042D01*
Y319214D01*
X46600Y320939D01*
Y324422D01*
X45257Y325765D01*
X44235D01*
X42435Y327565D01*
Y342568D01*
X31500Y353503D01*
Y374698D01*
X39200Y382398D01*
Y389735D01*
X37735Y391200D01*
G01X44525Y391650D02*
X44325D01*
X44275Y391600D01*
X42130D01*
X40730Y393000D01*
X36699D01*
X28200Y384501D01*
Y352475D01*
X39375Y341300D01*
Y333051D01*
X36795Y330471D01*
Y326416D01*
X45265Y317946D01*
Y316774D01*
X49395Y312644D01*
Y269458D01*
X45868Y265931D01*
Y238668D01*
X49201Y235335D01*
X52237D01*
X53765Y233807D01*
Y223602D01*
X48023Y217860D01*
G01X145000Y90700D02*
X147000Y88700D01*
Y85500D01*
X143700Y82200D01*
X141196D01*
X115800Y56804D01*
Y50800D01*
X113300Y48300D01*
X54600D01*
X48665Y54235D01*
Y66087D01*
X47805Y66947D01*
Y83101D01*
X56990Y92286D01*
Y108154D01*
X63240Y114404D01*
Y132310D01*
X64621Y133691D01*
Y153685D01*
X67220Y156284D01*
X67814Y156530D01*
X69530D01*
X70535Y157535D01*
Y160595D01*
X70205Y160925D01*
X67530D01*
X60771Y167684D01*
Y180671D01*
X57058Y184384D01*
Y190748D01*
X55175Y195293D01*
Y204081D01*
X56500Y205406D01*
Y207484D01*
X55295Y208689D01*
Y234441D01*
X52871Y236865D01*
X49835D01*
X47398Y239302D01*
Y265297D01*
X50925Y268824D01*
Y313278D01*
X46795Y317408D01*
Y318580D01*
X40905Y324470D01*
Y341934D01*
X29730Y353109D01*
Y381230D01*
X30110Y381610D01*
X35101D01*
G01X52410Y190190D02*
X54213Y188387D01*
Y182987D01*
X57850Y179350D01*
Y134150D01*
X56925Y133225D01*
Y116145D01*
X51141Y110361D01*
Y103097D01*
X50280Y102236D01*
Y91590D01*
X44100Y85410D01*
Y66303D01*
X45718Y64685D01*
Y44368D01*
X51048Y39038D01*
X59451D01*
X61669Y36820D01*
X172398D01*
X189242Y53664D01*
X209142D01*
G01X68600Y159160D02*
X67540Y158100D01*
X66939D01*
X65268Y157408D01*
X63091Y154150D01*
Y135711D01*
X62330Y134950D01*
X60506D01*
X58180Y132624D01*
Y115061D01*
X55460Y112341D01*
Y92920D01*
X46275Y83735D01*
Y66087D01*
X47025Y65337D01*
Y52975D01*
X53500Y46500D01*
X55000D01*
X56000Y45500D01*
Y42445D01*
X57500Y40945D01*
X60352D01*
X63229Y38068D01*
X71000D01*
X71500Y38568D01*
Y44600D01*
X73600Y46700D01*
X115000D01*
X117900Y49600D01*
Y56200D01*
X121600Y59900D01*
X133000D01*
G01X40340Y100710D02*
X43210D01*
X48513Y106013D01*
Y109954D01*
X55420Y116861D01*
Y133099D01*
X56275Y135164D01*
Y139305D01*
X56500Y139530D01*
Y178950D01*
X50645Y184805D01*
Y193706D01*
X44719Y199632D01*
Y217053D01*
X50235Y222569D01*
Y232795D01*
X51010Y233570D01*
G01X68600Y159160D02*
X67131D01*
X59241Y167050D01*
Y180037D01*
X55443Y183835D01*
Y190648D01*
X45949Y200142D01*
Y215786D01*
X48023Y217860D01*
G01X39100Y321600D02*
X41735Y318965D01*
Y316306D01*
X44693Y313349D01*
X44733Y313307D01*
X45600Y312439D01*
Y300149D01*
X48165Y297584D01*
Y269968D01*
X44638Y266441D01*
Y238158D01*
X49005Y233791D01*
Y223079D01*
X43489Y217563D01*
Y214589D01*
X39900Y211000D01*
G01X44500Y348000D02*
X45599D01*
X47800Y345799D01*
Y336300D01*
X54710Y329390D01*
Y317393D01*
X57670Y314433D01*
Y309657D01*
X54915Y306902D01*
Y254340D01*
X65650Y243605D01*
Y235846D01*
X62290Y232486D01*
Y226172D01*
X63145Y225317D01*
Y202730D01*
X64050Y201825D01*
Y201010D01*
G01X44341Y406480D02*
X45841D01*
X47550Y404771D01*
Y396014D01*
X50070Y393494D01*
Y387906D01*
X47550Y385386D01*
Y375300D01*
X47520Y375270D01*
Y362430D01*
X46990Y361900D01*
X41800D01*
X41400Y361500D01*
Y352100D01*
X43700Y349800D01*
X46300D01*
X49200Y346900D01*
Y336556D01*
X58600Y327156D01*
Y309271D01*
X55845Y306516D01*
Y254726D01*
X63011Y247560D01*
X70385D01*
X72355Y249530D01*
X78570D01*
X80270Y247830D01*
G01X52330Y413350D02*
Y410792D01*
X48780Y407242D01*
Y396120D01*
X51000Y393900D01*
Y387520D01*
X48780Y385300D01*
Y359680D01*
X46600Y357500D01*
X43300D01*
X42500Y356700D01*
Y354430D01*
X43330Y353600D01*
X45199D01*
X50400Y348399D01*
Y336672D01*
X59970Y327102D01*
Y323014D01*
X63000Y319984D01*
Y311233D01*
X56775Y305008D01*
Y255112D01*
X63397Y248490D01*
X69999D01*
X75278Y253769D01*
X77384D01*
G01X60225Y336099D02*
X53400Y342924D01*
Y352200D01*
X58100Y356900D01*
Y366101D01*
X60600Y368601D01*
Y385300D01*
X54095Y391805D01*
Y414083D01*
X53063Y415115D01*
X51216D01*
X46901Y410800D01*
X45000D01*
X42900Y412900D01*
G01X81355Y377883D02*
X79738Y379500D01*
X77400D01*
X76700Y378800D01*
Y377300D01*
X75600Y376200D01*
X71000D01*
X70400Y376800D01*
Y379000D01*
X69900Y379500D01*
X67100D01*
X66600Y379000D01*
X65200D01*
X64100Y380100D01*
Y396500D01*
X56800Y403800D01*
Y413542D01*
X53647Y416695D01*
X44919D01*
X40400Y421214D01*
Y425130D01*
X43600Y428330D01*
Y434500D01*
X42200Y435900D01*
G01X93916Y387332D02*
X92348Y388900D01*
X70430D01*
X65030Y394300D01*
Y396886D01*
X60385Y401531D01*
Y411273D01*
X53788Y417870D01*
X45060D01*
X41330Y421600D01*
Y424744D01*
X44530Y427944D01*
Y435230D01*
X45100Y435800D01*
G01X92360Y394175D02*
X90485Y392300D01*
X68063D01*
X65960Y394403D01*
Y397272D01*
X61400Y401832D01*
Y411574D01*
X54174Y418800D01*
X50100D01*
X46100Y422800D01*
G01X86481Y407871D02*
X85672D01*
X84701Y406900D01*
X65900D01*
X65235Y407565D01*
Y409479D01*
X54684Y420030D01*
X51371D01*
X49600Y421801D01*
Y434800D01*
X48050Y436350D01*
G01X50710Y54724D02*
X52311Y56325D01*
Y64689D01*
X49400Y67600D01*
Y81500D01*
X50973Y83073D01*
X59026D01*
X59750Y83797D01*
Y108750D01*
X64770Y113770D01*
Y131530D01*
X66151Y132911D01*
Y153051D01*
X67930Y154830D01*
X68341Y155000D01*
X70500D01*
X74300Y158800D01*
Y161299D01*
X71914Y163685D01*
X68674D01*
X63531Y168828D01*
Y181815D01*
X59846Y185500D01*
Y191230D01*
X57935Y195845D01*
Y202936D01*
X60588Y205589D01*
Y224394D01*
X58055Y226927D01*
Y243045D01*
X50700Y250400D01*
G01X58000Y217700D02*
X57058Y216758D01*
Y212442D01*
X59358Y210142D01*
Y206099D01*
X56705Y203446D01*
Y195598D01*
X58588Y191053D01*
Y185018D01*
X62301Y181305D01*
Y168318D01*
X68164Y162455D01*
X71404D01*
X72300Y161559D01*
Y159400D01*
G01X76200Y247400D02*
Y246200D01*
X73760Y243760D01*
X70662D01*
X66880Y239978D01*
Y235336D01*
X63775Y232231D01*
Y226427D01*
X64375Y225827D01*
Y204045D01*
X66445Y201975D01*
Y199505D01*
X63440Y196500D01*
Y191454D01*
X62306Y190320D01*
Y186520D01*
X65991Y182835D01*
Y173708D01*
X69095Y170604D01*
X70842D01*
X73550Y167896D01*
Y166680D01*
G01X52765Y390200D02*
Y386165D01*
X50010Y383410D01*
Y357310D01*
X49400Y356700D01*
Y351139D01*
X51630Y348909D01*
Y341270D01*
X62200Y330700D01*
X83325D01*
X85705Y333080D01*
X100410D01*
X102760Y330730D01*
Y328041D01*
X104765Y326036D01*
Y315834D01*
X107100Y313499D01*
Y304441D01*
X107570Y303971D01*
Y303930D01*
X112846Y298654D01*
X113824Y296293D01*
Y289493D01*
X123065Y280252D01*
Y272796D01*
X126385Y269476D01*
X127507D01*
X130525Y266458D01*
Y264994D01*
X129492Y263961D01*
Y263748D01*
X130739Y262501D01*
Y255240D01*
X129592Y254093D01*
Y241422D01*
X134700Y233779D01*
Y230411D01*
X134358Y230069D01*
G01X62458Y343275D02*
X66933Y338800D01*
X73399D01*
X79099Y344500D01*
X98100D01*
X105100Y337500D01*
Y332640D01*
X109847Y327893D01*
Y305398D01*
X114775Y300470D01*
X116284Y296822D01*
Y290513D01*
X126130Y280667D01*
Y279002D01*
X130600Y274532D01*
Y269863D01*
X133695Y266768D01*
Y262145D01*
X136870Y258970D01*
Y255391D01*
X136871Y255390D01*
Y254372D01*
X132052Y249553D01*
Y242170D01*
X135705Y236705D01*
X135805Y236664D01*
X137335Y236030D01*
X137337Y236029D01*
X137984Y235761D01*
X138109Y235709D01*
X138110Y235707D01*
X143560Y233449D01*
X149216Y229671D01*
X151810Y227077D01*
Y224069D01*
X155954Y219928D01*
X157110Y217137D01*
Y213370D01*
X158239Y212241D01*
Y207735D01*
X161700Y204274D01*
Y202457D01*
X164648Y199509D01*
X166308D01*
X170604Y203805D01*
X175196D01*
G01X71700Y340600D02*
X67700Y344600D01*
Y344900D01*
X64100Y348500D01*
Y357200D01*
X62458Y358842D01*
Y365658D01*
X64400Y367600D01*
X101710D01*
X107570Y373460D01*
X116154D01*
X124295Y365319D01*
Y359895D01*
X119690Y355290D01*
Y344881D01*
X121730Y342841D01*
Y323053D01*
X127872Y316911D01*
Y309373D01*
X133104Y304141D01*
Y294728D01*
X138244Y289588D01*
X139369D01*
X147310Y281647D01*
X149553D01*
X154275Y276925D01*
Y261694D01*
X155025Y260944D01*
Y253064D01*
X156324Y251765D01*
X157384D01*
X172414Y236735D01*
Y233914D01*
X173428Y232900D01*
X176520D01*
X179811Y229609D01*
Y228188D01*
X181495Y226504D01*
Y225852D01*
G01X62458Y355873D02*
X60993Y357338D01*
Y365493D01*
X64000Y368500D01*
X101210D01*
X107270Y374560D01*
X116087D01*
X125025Y365622D01*
Y359124D01*
X120620Y354719D01*
Y345267D01*
X122660Y343227D01*
Y323439D01*
X128802Y317297D01*
Y309759D01*
X134034Y304527D01*
Y295114D01*
X138630Y290518D01*
X139755D01*
X146093Y284180D01*
X148690D01*
X155205Y277665D01*
Y262080D01*
X155955Y261330D01*
Y258823D01*
X158735Y256043D01*
Y251730D01*
X174265Y236200D01*
X176701D01*
X183094Y229807D01*
Y228307D01*
X184645Y226756D01*
Y225852D01*
G01X181495Y222703D02*
X183098Y221100D01*
X185800D01*
X186300Y221600D01*
Y230000D01*
X185800Y230500D01*
X184000D01*
X177500Y237000D01*
X174782D01*
X162738Y249044D01*
Y255762D01*
X158800Y259700D01*
Y263918D01*
X157740Y264978D01*
Y276563D01*
X148863Y285440D01*
X147465D01*
X140527Y292378D01*
X139402D01*
X136295Y295485D01*
Y304899D01*
X130662Y310532D01*
Y321433D01*
X127730Y324365D01*
Y333013D01*
X128605Y333888D01*
Y336124D01*
X128595Y336134D01*
Y338718D01*
X127730Y339583D01*
Y342586D01*
X127400Y342916D01*
Y346836D01*
X126865Y347371D01*
Y354936D01*
X126285Y355516D01*
Y366486D01*
X127500Y367701D01*
Y369799D01*
X124342Y372957D01*
Y379900D01*
X123842Y380400D01*
X119400D01*
X114760Y375760D01*
X107170D01*
X100710Y369300D01*
X63300D01*
X59900Y365900D01*
Y355616D01*
X58564Y354280D01*
G01X59511Y424477D02*
X58900Y423866D01*
Y417978D01*
X65478Y411400D01*
X75555D01*
X77592Y413437D01*
G01X109121Y69500D02*
X108821Y69200D01*
X105500D01*
X100600Y74100D01*
Y76900D01*
X98970Y78530D01*
Y87914D01*
X97300Y89584D01*
Y114430D01*
X96735Y114995D01*
Y124293D01*
X91095Y129933D01*
Y159511D01*
X80401Y170205D01*
X72981D01*
X70860Y172326D01*
Y173898D01*
X67221Y177537D01*
Y183345D01*
X63536Y187030D01*
Y189810D01*
X64670Y190944D01*
Y195990D01*
X67675Y198995D01*
Y202707D01*
X65605Y204777D01*
Y226337D01*
X65005Y226937D01*
Y231721D01*
X68670Y235386D01*
Y236868D01*
X71217Y239415D01*
X71855D01*
X80270Y247830D01*
G01X107124Y71004D02*
X107705Y71585D01*
Y76723D01*
X102600Y81828D01*
Y85600D01*
X98230Y89970D01*
Y114816D01*
X97665Y115381D01*
Y124679D01*
X92025Y130319D01*
Y159897D01*
X80787Y171135D01*
X73367D01*
X71790Y172712D01*
Y174284D01*
X69340Y176734D01*
Y193120D01*
X67558Y194902D01*
Y197562D01*
X68605Y198609D01*
Y203093D01*
X66535Y205163D01*
Y226723D01*
X65935Y227323D01*
Y231335D01*
X69600Y235000D01*
Y236482D01*
X71603Y238485D01*
X72386D01*
X79501Y245600D01*
X81201D01*
X82405Y246804D01*
Y250395D01*
X79031Y253769D01*
X77384D01*
G01X67700Y229725D02*
X67765Y229660D01*
Y213320D01*
X74960Y206125D01*
Y188542D01*
X77150Y186352D01*
Y179750D01*
X75965Y178565D01*
X71124D01*
G01X106000Y91900D02*
X105500Y92400D01*
Y97500D01*
X99995Y103005D01*
Y114367D01*
X98595Y115767D01*
Y125065D01*
X92955Y130705D01*
Y160284D01*
X78100Y175139D01*
Y178468D01*
X78925Y179293D01*
Y186300D01*
X78100Y188293D01*
Y189079D01*
X76750Y192339D01*
Y206188D01*
X74905Y208033D01*
Y209505D01*
X77825Y212425D01*
Y232065D01*
X87430Y241670D01*
Y273930D01*
X92300Y278800D01*
Y282100D01*
G01X65755Y256045D02*
X64000Y257800D01*
Y264400D01*
X68200Y268600D01*
Y280899D01*
X71700Y284399D01*
Y297963D01*
X69705Y299958D01*
Y305294D01*
X67735Y307264D01*
Y309432D01*
X69705Y311402D01*
Y317206D01*
X72599Y320100D01*
X82400D01*
X83500Y321200D01*
Y324700D01*
X85500Y326700D01*
G01X92698Y323224D02*
X87774Y318300D01*
X73000D01*
X71265Y316565D01*
Y307968D01*
X70935Y307638D01*
Y300468D01*
X72930Y298473D01*
Y283889D01*
X71800Y282759D01*
Y263230D01*
X69035Y260465D01*
X68990D01*
G01X150619Y178646D02*
X146305Y182960D01*
X135230D01*
X128045Y190145D01*
Y192042D01*
X132270Y196267D01*
Y201625D01*
X129790Y204105D01*
Y213466D01*
X126100Y217156D01*
Y223217D01*
X126700Y223817D01*
Y229800D01*
X124672Y231828D01*
Y252408D01*
X123305Y253775D01*
Y260495D01*
X119600Y264200D01*
Y267474D01*
X116174Y270900D01*
X114600D01*
X112900Y272600D01*
Y277201D01*
X109835Y280266D01*
Y284066D01*
X103001Y290900D01*
X99600D01*
X90710Y299790D01*
Y312850D01*
X89260Y314300D01*
X74000D01*
X73400Y313700D01*
G01X150005Y184973D02*
X149492Y184460D01*
X142581D01*
X137200Y189841D01*
Y191060D01*
X137170Y191090D01*
Y200205D01*
X132250Y205125D01*
Y214486D01*
X128560Y218176D01*
Y222197D01*
X129530Y223167D01*
Y230710D01*
X129329Y230911D01*
X127132Y234199D01*
Y253428D01*
X125765Y254795D01*
Y266615D01*
X120445Y271935D01*
X119064D01*
X118290Y272709D01*
Y279410D01*
X118280Y279420D01*
Y281557D01*
X110242Y289595D01*
X108946D01*
X96210Y302331D01*
Y307879D01*
X95997Y308393D01*
X95370Y309020D01*
X93820D01*
X92390Y310450D01*
Y312910D01*
X89200Y316100D01*
X77500D01*
G01X75056Y346425D02*
X72075D01*
X70300Y348200D01*
Y353300D01*
X71200Y354200D01*
X72800D01*
X73500Y354900D01*
Y359900D01*
X74088Y360488D01*
X106004D01*
X111600Y354892D01*
Y342801D01*
X113100Y341301D01*
Y335101D01*
X117410Y330791D01*
Y319520D01*
X119774Y317156D01*
Y310469D01*
X119773Y310468D01*
Y309450D01*
X127554Y301669D01*
Y292426D01*
X135942Y284038D01*
X137067D01*
X141760Y279345D01*
Y277644D01*
X143602Y275802D01*
Y270523D01*
X147425Y266700D01*
Y260692D01*
X149475Y258642D01*
Y254476D01*
X146869Y251870D01*
X145223D01*
X142280Y248927D01*
Y243022D01*
X143246Y241577D01*
X144156Y241200D01*
X150610D01*
X153862Y244452D01*
X156507D01*
X163300Y237659D01*
Y233804D01*
X168073Y229031D01*
Y225179D01*
X169944Y220659D01*
X171668Y218935D01*
X173135D01*
X173700Y219500D01*
X175600D01*
X180000Y215100D01*
Y211758D01*
X178346Y210104D01*
G01X181495Y206955D02*
Y213253D01*
X183160Y214918D01*
Y216950D01*
X182090Y218020D01*
X180480D01*
X174865Y223635D01*
X173148D01*
X173012Y223691D01*
X172053Y224650D01*
X172035Y224693D01*
X171463Y226071D01*
Y230437D01*
X168900Y233000D01*
Y235647D01*
X155872Y248675D01*
X155041D01*
X151935Y251781D01*
Y259662D01*
X151090Y260507D01*
Y270154D01*
X144220Y277024D01*
Y280365D01*
X138087Y286498D01*
X136962D01*
X130014Y293446D01*
Y302689D01*
X122234Y310469D01*
Y318176D01*
X118640Y321770D01*
Y331301D01*
X118200Y331741D01*
Y341999D01*
X116600Y343599D01*
Y355370D01*
X115000Y356970D01*
Y365000D01*
X112830Y367170D01*
X110971D01*
X107658Y363857D01*
X71157D01*
X70300Y363000D01*
Y354700D01*
X69800Y354200D01*
X67992D01*
X67292Y353500D01*
Y347890D01*
X68757Y346425D01*
G01X178346Y206955D02*
X176666Y208635D01*
X174593D01*
X174032Y209196D01*
X173896Y209399D01*
X173600Y210114D01*
Y211600D01*
X172400Y212800D01*
X169803D01*
X168147Y214456D01*
X161244D01*
X160800Y214900D01*
Y217930D01*
X159036Y222189D01*
X155500Y225722D01*
Y228607D01*
X151560Y232547D01*
X145712Y236454D01*
X145660Y236579D01*
X138223Y239659D01*
X138220D01*
X138152Y239688D01*
X136000Y242908D01*
Y248001D01*
X143485Y255486D01*
Y257615D01*
X139135Y261965D01*
Y275049D01*
X137926Y276258D01*
X135950D01*
X133550Y278658D01*
Y280350D01*
X122361Y291539D01*
Y292735D01*
X122365Y292739D01*
Y294203D01*
X122361Y294207D01*
Y294216D01*
X120791Y295786D01*
X118049Y302419D01*
X113537Y306931D01*
Y329423D01*
X109140Y333820D01*
Y339359D01*
X108029Y340470D01*
Y353283D01*
X106904Y354408D01*
X104100D01*
X100892Y351200D01*
X76580D01*
X75056Y352724D01*
G01Y349574D02*
X74026D01*
X73371Y350229D01*
Y353111D01*
X74668Y354408D01*
X101808D01*
X103200Y355800D01*
X106992D01*
X109200Y353592D01*
Y341200D01*
X110370Y340030D01*
Y334330D01*
X114767Y329933D01*
Y307441D01*
X120176Y302032D01*
Y300494D01*
X121831Y296500D01*
X123100Y295974D01*
G01X184645Y222703D02*
X183026Y223374D01*
X182013Y224387D01*
X180888D01*
X179811Y225464D01*
Y226459D01*
X178733Y227537D01*
X174589D01*
X173500Y228626D01*
Y230140D01*
X170554Y233086D01*
Y235733D01*
X156382Y249905D01*
X155552D01*
X153165Y252292D01*
Y260172D01*
X152370Y260967D01*
Y270614D01*
X145450Y277534D01*
Y280875D01*
X138597Y287728D01*
X137472D01*
X131244Y293956D01*
Y303199D01*
X125900Y308543D01*
Y316251D01*
X119870Y322281D01*
Y342069D01*
X117830Y344109D01*
Y356450D01*
X116600Y357680D01*
Y365400D01*
X114100Y367900D01*
X109600D01*
X108500Y366800D01*
X67700D01*
X67100Y366200D01*
Y354700D01*
X65607Y353207D01*
Y352724D01*
G01X117410Y381350D02*
X111250D01*
X100000Y370100D01*
X68000D01*
X67200Y370900D01*
Y376900D01*
X68183Y377883D01*
X68757D01*
G01X206692Y229002D02*
X205222Y227532D01*
X196168D01*
X195559Y228141D01*
Y229609D01*
X194701Y230467D01*
X193705D01*
X189836Y234336D01*
Y236704D01*
X180099Y246441D01*
X173281D01*
X171705Y248017D01*
Y259085D01*
X169527Y261263D01*
Y268861D01*
X161200Y277188D01*
Y286700D01*
X157600Y290300D01*
Y290384D01*
X157470Y290514D01*
Y294530D01*
X153400Y298600D01*
Y302200D01*
X150900Y304700D01*
X139800D01*
X132630Y311870D01*
Y327986D01*
X130465Y330151D01*
Y346403D01*
X128725Y348143D01*
Y355804D01*
X128145Y356384D01*
Y365246D01*
X129075Y366176D01*
Y370072D01*
X125802Y373345D01*
Y379302D01*
X128105Y381605D01*
Y384018D01*
X127608Y384515D01*
X125432D01*
X122869Y381952D01*
X119110D01*
X116522Y384540D01*
X110940D01*
X102700Y376300D01*
X77699D01*
X76132Y374733D01*
X75056D01*
G01X206692Y232151D02*
Y236108D01*
X202132Y240668D01*
X185408Y247592D01*
X184100Y248900D01*
Y256117D01*
X185100Y258532D01*
Y261502D01*
X178900Y267702D01*
Y275800D01*
X174214Y280486D01*
Y283146D01*
X156970Y300390D01*
Y300430D01*
X156785Y300615D01*
Y303775D01*
X152030Y308530D01*
X141424D01*
X139830Y310124D01*
Y326530D01*
X139095Y327265D01*
Y336505D01*
X136800Y338800D01*
X135000D01*
X133800Y340000D01*
Y341900D01*
X134365Y342465D01*
Y351355D01*
X133485Y352235D01*
Y355815D01*
X131235Y358065D01*
Y363136D01*
X132165Y364066D01*
Y373348D01*
X131195Y375688D01*
Y385300D01*
X128860Y387635D01*
X124372D01*
X124342Y387605D01*
X121858D01*
X121833Y387630D01*
X107230D01*
X105400Y385800D01*
X67402D01*
X67072Y385470D01*
Y382498D01*
X65607Y381033D01*
G01X71906Y377883D02*
X73500Y379477D01*
Y381700D01*
X74500Y382700D01*
X84800D01*
X88100Y379400D01*
X103600D01*
X109670Y385470D01*
X116908D01*
X119696Y382682D01*
X122283D01*
X125071Y385470D01*
X127969D01*
X129035Y384404D01*
Y381219D01*
X126532Y378716D01*
Y373931D01*
X130005Y370458D01*
Y365790D01*
X129075Y364860D01*
Y357070D01*
X129655Y356490D01*
Y348529D01*
X131395Y346789D01*
Y330706D01*
X137400Y324701D01*
Y309498D01*
X140898Y306000D01*
X150916D01*
X154330Y302586D01*
Y299470D01*
X158400Y295400D01*
Y290900D01*
X162130Y287170D01*
Y279600D01*
X163930Y277800D01*
X169000D01*
X169817Y276983D01*
X171422Y273108D01*
Y267422D01*
X172444Y266400D01*
X173700D01*
X176070Y264030D01*
Y259135D01*
X172635Y255700D01*
Y248404D01*
X173668Y247371D01*
X180485D01*
X191486Y236370D01*
X191693D01*
G01X104600Y50501D02*
Y50700D01*
X97296Y58004D01*
X90061D01*
X84500Y63565D01*
Y66500D01*
G01X112600Y52800D02*
X104643D01*
X93776Y63667D01*
X91772D01*
X89819Y65620D01*
Y68653D01*
X90151Y68985D01*
G01X95944Y149687D02*
Y149987D01*
X94185Y151746D01*
Y160794D01*
X79330Y175649D01*
Y177958D01*
X80155Y178783D01*
Y186545D01*
X79330Y188538D01*
Y189324D01*
X77980Y192586D01*
Y199547D01*
X79055Y200622D01*
Y231555D01*
X94600Y247100D01*
X95300D01*
G01X107200Y265000D02*
X106678D01*
X104735Y263057D01*
Y247765D01*
X106200Y246300D01*
Y239550D01*
X105380Y238730D01*
Y235980D01*
X103980Y234580D01*
X90788D01*
X83475Y227267D01*
Y199465D01*
X85553Y194448D01*
Y180661D01*
X86059Y178112D01*
X88329Y172633D01*
X103575Y157387D01*
Y143425D01*
X101215Y141065D01*
Y131085D01*
X104640Y127660D01*
Y126568D01*
X106870Y124338D01*
Y117534D01*
X108903Y115501D01*
X109350D01*
G01X109800Y264928D02*
X109252Y264380D01*
Y261281D01*
X108530Y260559D01*
Y238584D01*
X107736Y237790D01*
Y235040D01*
X104946Y232250D01*
X91754D01*
X85805Y226301D01*
Y206383D01*
X87883Y204305D01*
Y203166D01*
X87223Y202506D01*
X86600D01*
X85940Y201846D01*
Y200836D01*
X86600Y200176D01*
X87223D01*
X87883Y199516D01*
Y180891D01*
X88300Y178792D01*
X90305Y173953D01*
X105905Y158353D01*
Y142459D01*
X104170Y140724D01*
Y135767D01*
X106970Y132967D01*
Y127534D01*
X109200Y125304D01*
Y118500D01*
G01X111600Y262730D02*
Y258360D01*
X113230Y256730D01*
Y253369D01*
X110860Y250999D01*
Y237618D01*
X110066Y236824D01*
Y233966D01*
X106020Y229920D01*
X92720D01*
X88135Y225335D01*
Y207349D01*
X90213Y205271D01*
Y181140D01*
X90548Y179456D01*
X92280Y175274D01*
X108235Y159319D01*
Y141493D01*
X106500Y139758D01*
Y136733D01*
X109300Y133933D01*
Y128600D01*
X109200Y128500D01*
G01X81900Y337100D02*
X87050Y342250D01*
X98350D01*
X101200Y339400D01*
Y334800D01*
X108617Y327383D01*
Y304888D01*
X113702Y299803D01*
X115054Y296538D01*
Y290003D01*
X124900Y280157D01*
Y278200D01*
X126900Y276200D01*
Y271823D01*
X132465Y266258D01*
Y261635D01*
X135640Y258460D01*
Y254881D01*
X130822Y250063D01*
Y241796D01*
X132883Y238713D01*
X134890Y235710D01*
X137167Y234767D01*
X137169Y234764D01*
X142977Y232359D01*
X148434Y228713D01*
X150580Y226567D01*
Y223519D01*
X154941Y219158D01*
X155809Y217062D01*
Y212792D01*
X157009Y211592D01*
Y207225D01*
X160470Y203764D01*
Y201947D01*
X164138Y198279D01*
X166900D01*
X170961Y202340D01*
X180030D01*
X181495Y203805D01*
G01X78206Y359023D02*
X79729Y357500D01*
X106970D01*
X110300Y354170D01*
Y341899D01*
X111600Y340599D01*
Y334840D01*
X115997Y330443D01*
Y307951D01*
X122957Y300991D01*
G01X90766Y384182D02*
X92248Y382700D01*
X105399D01*
X109099Y386400D01*
X117294D01*
X120282Y383412D01*
X121697D01*
X124685Y386400D01*
X128355D01*
X129965Y384790D01*
Y380833D01*
X127262Y378130D01*
Y374517D01*
X130935Y370844D01*
Y365404D01*
X130005Y364474D01*
Y357456D01*
X130585Y356876D01*
Y348915D01*
X132500Y347000D01*
Y339560D01*
X134760Y337300D01*
X136400D01*
X137865Y335835D01*
Y326755D01*
X138600Y326020D01*
Y309614D01*
X140914Y307300D01*
X151000D01*
X155555Y302745D01*
Y299905D01*
X159330Y296130D01*
Y291286D01*
X170995Y279621D01*
Y277136D01*
X172866Y272620D01*
Y268667D01*
X173733Y267800D01*
Y267799D01*
X177000Y264532D01*
Y254536D01*
X174400Y251936D01*
G01X87800Y410300D02*
Y411100D01*
X88600Y411900D01*
X92400D01*
X94265Y410035D01*
Y405035D01*
X107733Y391567D01*
X120233D01*
X121300Y390500D01*
Y389800D01*
X122235Y388865D01*
X122338D01*
X122368Y388835D01*
X123832D01*
X123862Y388865D01*
X129370D01*
X132425Y385810D01*
Y375937D01*
X133395Y373595D01*
Y363906D01*
X134865Y362436D01*
Y357415D01*
X134715Y357265D01*
Y352745D01*
X135595Y351865D01*
Y341405D01*
X136000Y341000D01*
G01X110950Y82050D02*
X109500Y83500D01*
Y89000D01*
X111000Y90500D01*
Y93800D01*
X102800Y102000D01*
Y118755D01*
X102310Y119245D01*
Y123091D01*
X94635Y130766D01*
Y141235D01*
X98500Y145100D01*
Y151600D01*
X97200Y152900D01*
X95950D01*
G01X106100Y282900D02*
Y282520D01*
X104500Y280920D01*
Y274600D01*
X107500Y271600D01*
X112160D01*
X114881Y268879D01*
Y267884D01*
X117614Y261286D01*
X120900Y258000D01*
Y256047D01*
X121785Y255162D01*
Y253698D01*
X121365Y253278D01*
Y251168D01*
X120900Y250703D01*
Y237087D01*
X119435Y235622D01*
Y230627D01*
X118805Y229997D01*
Y221589D01*
X119996Y218714D01*
X127630Y211080D01*
Y203209D01*
X129800Y201039D01*
Y196853D01*
X125885Y192938D01*
Y189249D01*
X129005Y186129D01*
Y169000D01*
X124300Y164295D01*
Y155300D01*
X126300Y153300D01*
Y127400D01*
X128043Y125657D01*
X131656D01*
X133030Y124283D01*
Y119604D01*
X137966Y114668D01*
X142150D01*
X157578Y99240D01*
X171131D01*
X174461Y102570D01*
X176130D01*
X178570Y100130D01*
Y98830D01*
X180900Y96500D01*
X218150D01*
X222890Y101240D01*
G01X94400Y311100D02*
X95390D01*
X97028Y309462D01*
X97460Y308419D01*
Y302821D01*
X109456Y290825D01*
X110752D01*
X121835Y279742D01*
Y272285D01*
X126995Y267125D01*
Y264505D01*
X129509Y261991D01*
Y259109D01*
X127060Y256660D01*
Y255240D01*
X128362Y253938D01*
Y241048D01*
X131932Y235706D01*
Y223829D01*
X129790Y221687D01*
Y218686D01*
X138400Y210076D01*
Y191600D01*
X139600Y190400D01*
X141500D01*
X142900Y191800D01*
X146378D01*
X148215Y189963D01*
X149100D01*
G01X94400Y307200D02*
Y302401D01*
X108436Y288365D01*
X109732D01*
X117050Y281047D01*
Y272150D01*
X119200Y270000D01*
X120640D01*
X124535Y266105D01*
Y254285D01*
X125902Y252918D01*
Y232598D01*
X128300Y230200D01*
Y223677D01*
X127330Y222707D01*
Y217666D01*
X131020Y213976D01*
Y204615D01*
X133500Y202135D01*
Y195000D01*
X129810Y191310D01*
G01X95060Y327625D02*
X94670Y327235D01*
Y314240D01*
X97638Y311272D01*
X98359Y309531D01*
X99990Y307900D01*
G01X110565Y296331D02*
X110877Y296643D01*
Y298883D01*
X106340Y303420D01*
Y303461D01*
X103085Y306716D01*
Y309514D01*
X103056Y309543D01*
Y309729D01*
X103085Y309758D01*
Y313197D01*
X100795Y315487D01*
Y325755D01*
X95280Y331270D01*
X94269D01*
X93288Y330289D01*
G01X184645Y203805D02*
X184595D01*
X183100Y205300D01*
X168801D01*
X167636Y204135D01*
X165463D01*
X163328Y206270D01*
X161444D01*
X159469Y208245D01*
Y212751D01*
X158340Y213880D01*
Y217384D01*
X156911Y220834D01*
X153043Y224698D01*
X153040Y225471D01*
Y227587D01*
X150000Y230627D01*
X144135Y234546D01*
X138927Y236701D01*
X138926Y236703D01*
X137905Y237126D01*
X137902Y237127D01*
X137848Y237149D01*
X137846Y237150D01*
X136520Y237700D01*
X133282Y242545D01*
Y249043D01*
X138101Y253862D01*
Y255900D01*
X138100Y255901D01*
Y259480D01*
X134925Y262655D01*
Y267278D01*
X134195Y268008D01*
Y274533D01*
X132173Y276555D01*
X130317D01*
X127360Y279512D01*
Y281177D01*
X117514Y291023D01*
Y297273D01*
X115962Y301024D01*
X111077Y305909D01*
Y328403D01*
X106480Y333000D01*
Y338019D01*
X101800Y342699D01*
Y350500D01*
X103100Y351800D01*
X105591D01*
X106515Y352724D01*
G01X175196Y206955D02*
X175190D01*
X174765Y206530D01*
X168570D01*
X167200Y207900D01*
X164900D01*
X164500Y207500D01*
X161954D01*
X160700Y208754D01*
Y213260D01*
X159570Y214390D01*
Y217630D01*
X157955Y221530D01*
X156562Y222922D01*
X154272Y225210D01*
X154270Y225474D01*
Y228097D01*
X150779Y231588D01*
X144718Y235637D01*
X137792Y238505D01*
X137789Y238506D01*
X137336Y238694D01*
X134512Y242920D01*
Y248533D01*
X139331Y253352D01*
Y256410D01*
X139330Y256411D01*
Y259990D01*
X136155Y263165D01*
Y267788D01*
X135425Y268518D01*
Y275043D01*
X132683Y277785D01*
X130827D01*
X128590Y280022D01*
Y281687D01*
X118744Y291533D01*
Y297518D01*
X117005Y301722D01*
X112307Y306420D01*
Y328913D01*
X107710Y333510D01*
Y338889D01*
X105099Y341500D01*
Y348159D01*
X106514Y349574D01*
G01X96030Y409400D02*
Y406500D01*
X98030Y404500D01*
X102260D01*
X108490Y398270D01*
X110530D01*
X115468Y393332D01*
X119026D01*
G01X137900Y399500D02*
Y407384D01*
X132559Y412725D01*
X128968D01*
X126443Y415250D01*
X119443D01*
X115393Y419300D01*
X110299D01*
X109399Y420200D01*
X107500D01*
X105500Y418200D01*
G01X179217Y278528D02*
X179072D01*
X178650Y278950D01*
X178550D01*
X175444Y282056D01*
Y283656D01*
X158200Y300900D01*
Y304100D01*
X146600Y315700D01*
Y337600D01*
X140355Y343845D01*
Y350213D01*
X137020Y353548D01*
Y356514D01*
X137025Y356519D01*
Y363332D01*
X135555Y364802D01*
Y374028D01*
X134585Y376370D01*
Y386706D01*
X129945Y391346D01*
Y393230D01*
X128675Y394500D01*
Y404371D01*
X125019Y408027D01*
X111544D01*
X110101Y409470D01*
Y412326D01*
X108727Y413700D01*
X102400D01*
X98300Y409600D01*
Y407600D01*
G01X108336Y411547D02*
X106735Y409946D01*
Y406866D01*
X117801Y395800D01*
X119699D01*
X120835Y394664D01*
Y394249D01*
X121105Y393597D01*
X123100Y391602D01*
Y390600D01*
G01X215500Y247111D02*
X211789D01*
X207219Y251681D01*
X205204Y253028D01*
X203470Y256271D01*
Y259430D01*
X202640Y260260D01*
X199900D01*
X198500Y261660D01*
Y282800D01*
X190000Y291300D01*
Y298800D01*
X187700Y301100D01*
X186300D01*
X179240Y308160D01*
Y315460D01*
X178400Y316300D01*
X174899D01*
X174200Y316999D01*
Y320200D01*
X155200Y339200D01*
Y360701D01*
X154790Y361111D01*
Y367611D01*
X145100Y377301D01*
Y388917D01*
X148170Y391987D01*
Y399821D01*
X137400Y410591D01*
Y416600D01*
X135821Y418179D01*
X131805D01*
X130284Y419700D01*
X125020D01*
X122830Y417510D01*
X120552D01*
X116462Y421600D01*
X115298D01*
X113133Y423765D01*
X111902D01*
X109737Y421600D01*
X105458D01*
X104112Y422946D01*
G01X103461Y425875D02*
X105524D01*
X107799Y423600D01*
X109856D01*
X111351Y425095D01*
X113684D01*
X115849Y422930D01*
X117013D01*
X118103Y421840D01*
X129460D01*
X132191Y419109D01*
X142091D01*
X145700Y415500D01*
Y412900D01*
X144200Y411400D01*
Y406981D01*
X149500Y401681D01*
Y392000D01*
X146100Y388600D01*
Y378182D01*
X155774Y368508D01*
X156780D01*
X159583Y371311D01*
X160589D01*
X161302Y370598D01*
Y369592D01*
X156658Y364948D01*
Y363942D01*
X157371Y363229D01*
X158377D01*
X162290Y367142D01*
X162758D01*
X164009Y365891D01*
Y365423D01*
X161246Y362660D01*
Y358347D01*
X156205Y353306D01*
Y339895D01*
X166341Y329759D01*
X169408D01*
X172022Y332373D01*
X173027D01*
X173740Y331660D01*
Y330653D01*
X169942Y326855D01*
Y325849D01*
X170655Y325136D01*
X171661D01*
X174658Y328134D01*
X175664D01*
X176377Y327421D01*
Y326415D01*
X173380Y323417D01*
Y322411D01*
X174093Y321698D01*
X175099D01*
X178096Y324696D01*
X179102D01*
X179815Y323983D01*
Y322977D01*
X178790Y321951D01*
Y320010D01*
X180170Y318630D01*
Y308730D01*
X186500Y302400D01*
X191500D01*
X196443Y297457D01*
Y294065D01*
G01X112800Y60400D02*
Y65200D01*
X114735Y67135D01*
Y85465D01*
X113090Y87110D01*
Y108240D01*
X118000Y113150D01*
Y115997D01*
X117000Y116997D01*
Y135612D01*
X118692Y137304D01*
G01X227760Y82524D02*
Y83544D01*
X225374Y85930D01*
X201012D01*
X196618Y81536D01*
X164164D01*
X156255Y89445D01*
Y98171D01*
X144124Y110302D01*
X138684D01*
X135791Y113195D01*
Y114671D01*
X132286Y118176D01*
X130158D01*
X124765Y123569D01*
Y151283D01*
X119514Y156534D01*
Y173256D01*
X123144Y176886D01*
Y192544D01*
X121959Y193729D01*
Y210041D01*
X118472Y213528D01*
Y216389D01*
X116143Y222012D01*
Y230790D01*
G01X122330Y364670D02*
X120470D01*
X117800Y362000D01*
Y358880D01*
X118760Y357920D01*
Y344495D01*
X120800Y342455D01*
Y322667D01*
X126905Y316562D01*
Y309024D01*
X132174Y303755D01*
Y294342D01*
X137858Y288658D01*
X138983D01*
X146380Y281261D01*
Y278280D01*
X153345Y271315D01*
Y261308D01*
X154095Y260558D01*
Y252678D01*
X155938Y250835D01*
X156998D01*
X171484Y236349D01*
Y233528D01*
X175196Y229816D01*
Y229002D01*
G01X206051Y247911D02*
Y250249D01*
X204426Y251874D01*
X198698Y255705D01*
X197588Y257364D01*
X195743Y261818D01*
Y264500D01*
X195669Y264574D01*
Y270501D01*
X193600Y272570D01*
Y284200D01*
X185200Y292600D01*
Y300100D01*
X177200Y308100D01*
X175103D01*
X171400Y311803D01*
Y314701D01*
X173100Y316401D01*
Y319800D01*
X151654Y341246D01*
Y348454D01*
X153460Y350260D01*
Y362663D01*
X152921Y363202D01*
X150139D01*
X149600Y363741D01*
Y364503D01*
X150139Y365042D01*
X152921D01*
X153460Y365581D01*
Y366740D01*
X151036Y369164D01*
X150274D01*
X147137Y366027D01*
X146375D01*
X145835Y366567D01*
Y367329D01*
X148972Y370466D01*
Y371228D01*
X146274Y373926D01*
X145512D01*
X144124Y372538D01*
X143362D01*
X142822Y373078D01*
Y373840D01*
X144210Y375228D01*
Y375990D01*
X143000Y377200D01*
Y388700D01*
X145740Y391440D01*
Y400860D01*
X133200Y413400D01*
Y414899D01*
X130229Y417870D01*
X124639D01*
X122949Y416180D01*
X119829D01*
X115779Y420230D01*
X114170D01*
X112800Y421600D01*
G01X182435Y281797D02*
Y282165D01*
X180600Y284000D01*
Y287200D01*
X170900Y296900D01*
Y301000D01*
X168391Y303509D01*
X161592D01*
X153085Y312016D01*
Y334316D01*
X144265Y343136D01*
Y347619D01*
X137950Y353934D01*
Y356128D01*
X137955Y356133D01*
Y363718D01*
X136485Y365188D01*
Y374216D01*
X135515Y376558D01*
Y393812D01*
X132513Y396814D01*
X130486D01*
X129605Y397695D01*
Y404758D01*
X124863Y409500D01*
X111388D01*
X111031Y409857D01*
Y415431D01*
X111800Y416200D01*
X113000D01*
G01X108701Y418300D02*
X115075D01*
X119057Y414320D01*
X122567D01*
X130535Y406352D01*
Y398309D01*
X131100Y397744D01*
X132899D01*
X136445Y394198D01*
Y376743D01*
X137415Y374401D01*
Y365574D01*
X138885Y364104D01*
Y355747D01*
X138880Y355742D01*
Y354320D01*
X145195Y348005D01*
Y343806D01*
X156765Y332236D01*
Y315936D01*
X162001Y310700D01*
X170799D01*
X174599Y306900D01*
X176900D01*
X184000Y299800D01*
Y290900D01*
X186663Y288237D01*
Y279062D01*
X189040Y273322D01*
Y270360D01*
X189818Y269582D01*
Y260631D01*
X190851Y259598D01*
X193450D01*
X196226Y256822D01*
X198260Y253777D01*
X198283Y253744D01*
X202384Y250999D01*
X203270Y250113D01*
Y247715D01*
X213785Y237200D01*
X220100D01*
G01X146300Y161010D02*
X145610Y161700D01*
X132800D01*
X130900Y159800D01*
Y156800D01*
X129200Y155100D01*
Y136600D01*
X137300Y128500D01*
Y119658D01*
X139968Y116990D01*
X143112D01*
X158702Y101400D01*
X165400D01*
X171400Y107400D01*
X197600D01*
X209823Y119623D01*
X228087D01*
X230293Y117417D01*
G01X124226Y225194D02*
Y217290D01*
X128560Y212956D01*
Y203595D01*
X130900Y201255D01*
Y196637D01*
X126815Y192552D01*
Y189635D01*
X129935Y186515D01*
Y168300D01*
X128700Y167065D01*
Y156900D01*
X127500Y155700D01*
Y128200D01*
X128535Y127165D01*
X131464D01*
X133960Y124669D01*
Y119990D01*
X138277Y115673D01*
X142590D01*
X158093Y100170D01*
X170745D01*
X174075Y103500D01*
X189698D01*
X195198Y98000D01*
X211899D01*
X216964Y103065D01*
X234015D01*
X234455Y102625D01*
X238540D01*
X244115Y108200D01*
X246770D01*
X248790Y110220D01*
X259810D01*
X262610Y107420D01*
Y104111D01*
X264989Y101732D01*
G01X187794Y178646D02*
X188644Y177796D01*
X190324Y177100D01*
X193300D01*
X195000Y175400D01*
Y172200D01*
X192600Y169800D01*
Y165400D01*
X191700Y164500D01*
X187300D01*
X186200Y163400D01*
Y162200D01*
X185300Y161300D01*
X183600D01*
X183000Y160700D01*
Y158900D01*
X182300Y158200D01*
X180900D01*
X179900Y157200D01*
Y155140D01*
X175429Y150669D01*
X170109D01*
X166983Y147543D01*
X160743D01*
X153598Y140398D01*
X139582D01*
X136693Y143287D01*
Y143607D01*
X133500Y146800D01*
G01X208500Y126057D02*
X207043D01*
X205500Y127600D01*
X202000D01*
X201300Y126900D01*
X195129D01*
X188593Y124193D01*
X187770Y123370D01*
X174115Y120653D01*
X172303Y119903D01*
X166300Y113900D01*
X148040D01*
X143682Y118258D01*
X140570D01*
X138530Y120298D01*
Y137770D01*
X131200Y145100D01*
Y152500D01*
X134400Y155700D01*
X139100D01*
X142500Y159100D01*
X147600D01*
X148800Y160300D01*
X151400D01*
X154700Y163600D01*
Y165400D01*
X169500Y180200D01*
G01X122957Y300991D02*
X126324Y297624D01*
Y291916D01*
X135432Y282808D01*
X136557D01*
X140530Y278835D01*
Y277134D01*
X142032Y275632D01*
Y270163D01*
X146195Y266000D01*
Y260182D01*
X148245Y258132D01*
Y254986D01*
X146359Y253100D01*
X144713D01*
X141050Y249437D01*
Y242648D01*
X142429Y240584D01*
X144078Y239900D01*
X153999D01*
X155764Y238135D01*
X156985D01*
X159250Y235870D01*
Y229450D01*
X165435Y223265D01*
Y221732D01*
X168372Y218795D01*
X174307Y216335D01*
X175265D01*
X176700Y214900D01*
Y211608D01*
X175196Y210104D01*
G01Y213254D02*
X172841Y215609D01*
X167671Y217754D01*
X164111Y221314D01*
Y222488D01*
X161917Y224682D01*
X158911D01*
X157878Y225715D01*
Y231608D01*
X158020Y231750D01*
Y235360D01*
X156475Y236905D01*
X152625D01*
X151800Y236080D01*
X149709D01*
X147589Y238200D01*
X144962D01*
X141614Y239589D01*
X139820Y242273D01*
Y249947D01*
X144273Y254400D01*
X145919D01*
X147015Y255496D01*
Y257622D01*
X140500Y264137D01*
Y275424D01*
X139300Y276624D01*
Y278325D01*
X136047Y281578D01*
X134922D01*
X125094Y291406D01*
Y293980D01*
X123100Y295974D01*
G01X138600Y295900D02*
Y304199D01*
X131700Y311099D01*
Y323900D01*
X129800Y325800D01*
G01X141890Y310570D02*
Y326210D01*
X140325Y327775D01*
Y340058D01*
X136825Y343558D01*
Y352375D01*
X135945Y353255D01*
Y356755D01*
X136095Y356905D01*
Y362946D01*
X134625Y364416D01*
Y373842D01*
X133655Y376184D01*
Y386320D01*
X129880Y390095D01*
X126206D01*
X125174Y391127D01*
Y393916D01*
G01X142702Y227817D02*
Y226498D01*
X143719Y225481D01*
Y223581D01*
X148950Y218350D01*
Y213544D01*
X159240Y203254D01*
Y201437D01*
X164077Y196600D01*
X172700D01*
X173600Y197500D01*
Y198300D01*
X174490Y199190D01*
X180030D01*
X181495Y200655D01*
G01X138600Y295900D02*
Y295808D01*
X148038Y286370D01*
X152927D01*
X158670Y280627D01*
Y276162D01*
X167067Y267765D01*
Y260243D01*
X169245Y258065D01*
Y246996D01*
X172260Y243981D01*
X179079D01*
X186560Y236500D01*
Y234340D01*
X191500Y229400D01*
Y226100D01*
X193432Y224168D01*
X194701D01*
X195559Y223310D01*
Y222041D01*
X196367Y221233D01*
X204533D01*
X205079Y221779D01*
Y224239D01*
X206692Y225852D01*
G01X203542D02*
X201990Y224300D01*
X196700D01*
X195559Y225441D01*
Y226459D01*
X194701Y227317D01*
X193683D01*
X192500Y228500D01*
Y229932D01*
X188216Y234216D01*
Y236584D01*
X179589Y245211D01*
X172771D01*
X170475Y247507D01*
Y258575D01*
X168297Y260753D01*
Y268277D01*
X159900Y276674D01*
Y281137D01*
X153437Y287600D01*
X149305D01*
X147500Y289405D01*
G01X170800Y317600D02*
Y320200D01*
X146525Y344475D01*
Y349357D01*
X146195Y349687D01*
X145394D01*
X145000Y350081D01*
Y351197D01*
X145330Y351527D01*
X150627D01*
X151400Y352300D01*
Y353800D01*
X150665Y354535D01*
X148603D01*
X146822Y356316D01*
X142052D01*
X141045Y355309D01*
G01X197155Y314223D02*
Y314670D01*
X196900Y314925D01*
Y335000D01*
X188600Y343300D01*
Y349400D01*
X187700Y350300D01*
Y363400D01*
X196986Y372686D01*
Y374412D01*
X195698Y375700D01*
X182800D01*
X180000Y372900D01*
X153263D01*
X147200Y378963D01*
Y388301D01*
X151265Y392366D01*
Y399500D01*
G01X187794Y175496D02*
X186190Y177100D01*
X176600D01*
X161100Y161600D01*
Y160100D01*
X159900Y158900D01*
Y155600D01*
G01X152500Y199500D02*
X154100Y201100D01*
X157900D01*
X159100Y199900D01*
X159300D01*
X163634Y195566D01*
X172966D01*
X173200Y195800D01*
X182100D01*
X183100Y196800D01*
Y201600D01*
X183700Y202200D01*
X185600D01*
X186400Y203000D01*
Y207600D01*
X185400Y208600D01*
X183500D01*
X182687Y209413D01*
Y213412D01*
X186575Y217300D01*
X192800D01*
X194094Y218594D01*
Y219553D01*
G01X165500Y236100D02*
X166500D01*
X167670Y234930D01*
Y232490D01*
X170233Y229927D01*
Y225825D01*
X171008Y223955D01*
X171336Y223463D01*
X172038Y222761D01*
X172904Y222405D01*
X174242D01*
X180244Y216403D01*
X181495D01*
G01X187794Y219553D02*
X187953D01*
X189400Y221000D01*
Y230000D01*
X185450Y233950D01*
G01X182700Y342216D02*
X179916D01*
X175166Y337466D01*
X161932D01*
X158500Y340898D01*
X158459D01*
G01X200300Y328800D02*
Y333400D01*
X193000Y340700D01*
Y351500D01*
X194100Y352600D01*
Y360200D01*
X200100Y366200D01*
Y373500D01*
X196896Y376704D01*
X161154D01*
G01X169700Y102250D02*
X171085D01*
X173565Y104730D01*
X190632D01*
X195862Y99500D01*
X211659D01*
X216454Y104295D01*
X232770D01*
X233810Y105335D01*
Y106537D01*
X237778Y110505D01*
X247335D01*
X248880Y112050D01*
X250314D01*
X254900Y116636D01*
Y126100D01*
X242195Y138805D01*
Y141003D01*
G01X171600Y114000D02*
Y116600D01*
X173730Y118730D01*
X176450Y119857D01*
X189751Y122503D01*
X194600D01*
X195139Y123042D01*
Y124861D01*
X195678Y125400D01*
X196440D01*
X196979Y124861D01*
Y123042D01*
X197518Y122503D01*
X198280D01*
X198819Y123042D01*
Y124861D01*
X199358Y125400D01*
X200120D01*
X200659Y124861D01*
Y123042D01*
X201198Y122503D01*
X201960D01*
X202499Y123042D01*
Y123370D01*
X202829Y123700D01*
X204009D01*
X204339Y123370D01*
Y123042D01*
X204878Y122503D01*
X209320D01*
X209859Y123042D01*
Y124070D01*
X210189Y124400D01*
X211369D01*
X211699Y124070D01*
Y123042D01*
X212238Y122503D01*
X213000D01*
X213539Y123042D01*
Y124861D01*
X214078Y125400D01*
X214840D01*
X215379Y124861D01*
Y123042D01*
X215918Y122503D01*
X217408D01*
X217950Y123045D01*
Y124358D01*
X218492Y124900D01*
X219258D01*
X219800Y124358D01*
Y123045D01*
X220342Y122503D01*
X229281D01*
X230314Y121470D01*
X245793D01*
X249139Y124816D01*
Y129862D01*
X248401Y130600D01*
X245520D01*
G01X168392Y298493D02*
Y296727D01*
X177000Y288119D01*
Y284700D01*
X181700Y280000D01*
Y275600D01*
X180370Y274270D01*
Y269000D01*
X182470Y266900D01*
X185400D01*
X187158Y265142D01*
Y257958D01*
X185671Y256471D01*
X185400Y255817D01*
Y252930D01*
X192228Y246102D01*
X203857Y241286D01*
X209746Y235397D01*
G01X170550Y304050D02*
Y303850D01*
X172800Y301600D01*
Y297700D01*
X184200Y286300D01*
Y277800D01*
X185800Y276200D01*
Y271500D01*
X185000Y270700D01*
G01X182865Y113706D02*
Y113335D01*
X184900Y111300D01*
X186900D01*
X188911Y113311D01*
Y119211D01*
X190763Y121063D01*
X228684D01*
X229717Y120030D01*
X250404D01*
X250534Y119900D01*
X253100D01*
G01X226710Y364815D02*
X226695Y364800D01*
X221900D01*
X219000Y361900D01*
Y355040D01*
X217605Y353645D01*
Y342393D01*
X218770Y341228D01*
Y330970D01*
X209646Y321846D01*
Y271045D01*
X208830Y270229D01*
Y262370D01*
X213745Y257455D01*
Y252568D01*
X214768Y251545D01*
X218215D01*
X222280Y247480D01*
Y244421D01*
X222765Y243936D01*
Y241805D01*
X221949Y240989D01*
Y235965D01*
X220684Y234700D01*
X219672D01*
X217788Y232816D01*
Y219088D01*
X216350Y217650D01*
X196449D01*
X195559Y218540D01*
Y220160D01*
X194701Y221018D01*
X193081D01*
X191397Y222702D01*
X190944D01*
G01X191693Y236370D02*
X193031D01*
X195559Y233842D01*
Y231142D01*
X196201Y230500D01*
X207273D01*
X208162Y229611D01*
Y221023D01*
X206692Y219553D01*
G01X183625Y273500D02*
Y273100D01*
X182700Y272175D01*
Y269500D01*
X183665Y268535D01*
X186865D01*
X188488Y266912D01*
Y259585D01*
X190624Y254428D01*
X195076Y249976D01*
X200323D01*
X201155Y249144D01*
Y247948D01*
X214461Y234642D01*
Y225274D01*
X212991Y223804D01*
Y222740D01*
G01X187400Y255700D02*
X186800Y255100D01*
Y254231D01*
X194107Y246924D01*
X204676Y242546D01*
X211490Y235732D01*
Y230503D01*
X212991Y229002D01*
G01X183800Y345400D02*
X184865Y344335D01*
Y340867D01*
X191430Y334302D01*
Y320089D01*
X190683Y319342D01*
Y307097D01*
X198726Y299054D01*
X198867Y298714D01*
X204126Y293455D01*
X207589Y285101D01*
X207900Y284345D01*
Y261599D01*
X212465Y257034D01*
Y252135D01*
X213985Y250615D01*
X217829D01*
X221000Y247444D01*
Y243000D01*
G01X215100Y244100D02*
X215999D01*
X217665Y245766D01*
Y248109D01*
X216498Y249276D01*
X211526D01*
X211523Y249277D01*
X208400Y252400D01*
Y257152D01*
X207665Y258254D01*
Y259197D01*
X203265Y263597D01*
Y266017D01*
X201997Y267285D01*
X201645D01*
X200600Y268852D01*
Y291051D01*
X197598Y298301D01*
X188326Y307573D01*
X187893Y308619D01*
Y316451D01*
X184700Y324159D01*
Y339151D01*
X182700Y341151D01*
Y342216D01*
G01X195800Y396780D02*
X205400Y387180D01*
Y357000D01*
X197711Y349311D01*
Y349250D01*
G01X232470Y382280D02*
X232289D01*
Y382262D01*
X230520Y380493D01*
Y376577D01*
X232265Y374832D01*
Y372662D01*
X231835Y372232D01*
Y366135D01*
X218835Y353135D01*
Y342903D01*
X220000Y341738D01*
Y329946D01*
X210876Y320822D01*
Y282924D01*
X215316Y278484D01*
Y267357D01*
X212269Y264310D01*
Y260750D01*
X216800Y256219D01*
Y255550D01*
G01X214175Y333740D02*
X214240Y333805D01*
Y339559D01*
X209700Y344099D01*
Y354310D01*
X209915Y358691D01*
Y365563D01*
X211175Y378358D01*
Y397141D01*
X213200Y399166D01*
G01X231500Y352500D02*
Y338400D01*
X229100Y336000D01*
Y330116D01*
X229616Y329600D01*
X232599D01*
X233840Y328359D01*
Y322843D01*
X231795Y320798D01*
Y300990D01*
X231005Y300200D01*
Y290015D01*
X232770Y288250D01*
Y279849D01*
X233700Y278919D01*
Y271200D01*
X234880Y270020D01*
Y264870D01*
X234030Y264020D01*
X232310D01*
X230060Y261770D01*
Y260400D01*
X231820Y258640D01*
Y253480D01*
X227040Y248700D01*
Y242550D01*
X224082Y239592D01*
Y228272D01*
X223342Y227532D01*
X222041D01*
X220850Y226341D01*
Y219026D01*
X221793Y218083D01*
X230707D01*
X233440Y215350D01*
Y197750D01*
X230172Y194482D01*
Y180772D01*
X229600Y180200D01*
X228030D01*
X227060Y179230D01*
Y176530D01*
X221550Y171020D01*
X218997D01*
X217730Y169753D01*
Y155510D01*
X227150Y146090D01*
Y126671D01*
X230911Y122910D01*
X245492D01*
X247909Y125327D01*
Y127470D01*
X247579Y127800D01*
X245500D01*
G01X225552Y159748D02*
Y158776D01*
X223923Y157147D01*
Y151412D01*
X236000Y139335D01*
Y127200D01*
X234900Y126100D01*
G01X219253Y156599D02*
X220813Y158159D01*
X222892D01*
X223942Y159209D01*
Y166516D01*
X225055Y167629D01*
X226063D01*
X227178Y168744D01*
Y174708D01*
X230200Y177730D01*
Y179300D01*
X233484Y182584D01*
Y193581D01*
X237013Y197110D01*
Y215543D01*
X239761Y218291D01*
Y220678D01*
X240198Y221115D01*
X242406D01*
X242955Y221664D01*
Y223730D01*
X243565Y224340D01*
X246125D01*
X247637Y225852D01*
G01X242690Y255300D02*
X237721Y251221D01*
X235924Y249424D01*
X235200Y247676D01*
X233400Y238627D01*
Y225000D01*
X232605Y224205D01*
X231282D01*
X230424Y223347D01*
Y222024D01*
X229560Y221160D01*
X228059D01*
X226452Y219553D01*
X225552D01*
G01X222402D02*
Y219602D01*
X224000Y221200D01*
X226300D01*
X227100Y222000D01*
Y223300D01*
X228100Y224300D01*
X229300D01*
X230300Y225300D01*
Y241400D01*
X232300Y243400D01*
Y249400D01*
X235500Y252600D01*
Y258670D01*
X236390Y259560D01*
X244760D01*
X257145Y271945D01*
Y279700D01*
G01X262100Y280700D02*
X260400Y282400D01*
X256500D01*
X254840Y280740D01*
Y277857D01*
X255700Y276997D01*
Y272905D01*
X243711Y260916D01*
X235286D01*
X233160Y258790D01*
Y252920D01*
X228370Y248130D01*
Y241370D01*
X227200Y240200D01*
Y224900D01*
X226600Y224300D01*
X223992D01*
X222440Y225852D01*
G01X222402Y229002D02*
X222900Y229500D01*
Y240200D01*
X224000Y241300D01*
Y244500D01*
X223510Y244990D01*
Y247990D01*
X218199Y253301D01*
X217181D01*
X217180Y253300D01*
X215520D01*
X215510Y253310D01*
G01X225275Y246000D02*
Y253771D01*
X225570Y254066D01*
Y255534D01*
X224850Y256254D01*
Y263240D01*
X222700Y265390D01*
Y287699D01*
X220020Y290379D01*
Y307136D01*
X225241Y319741D01*
X230445Y324945D01*
Y325945D01*
G01X228800Y312100D02*
X226700Y310000D01*
Y301680D01*
X227390Y300990D01*
Y278357D01*
X224630Y275597D01*
Y264790D01*
X226300Y263120D01*
Y257716D01*
X227316Y256700D01*
G01X219900Y267100D02*
X218500Y268500D01*
Y279377D01*
X217174Y280703D01*
Y292682D01*
X218680Y294188D01*
Y307406D01*
X222500Y316629D01*
Y326700D01*
X225650Y329850D01*
Y337520D01*
G01X214034Y261482D02*
Y264335D01*
X217170Y267471D01*
Y278826D01*
X215844Y280152D01*
Y293233D01*
X217126Y294515D01*
Y307499D01*
X221000Y316851D01*
Y327400D01*
X223165Y329565D01*
Y355725D01*
X235700Y368260D01*
Y390950D01*
X231990Y394660D01*
X222060D01*
X217390Y399330D01*
Y401340D01*
G01X223420Y367080D02*
X220130Y375024D01*
X217900Y386233D01*
Y394335D01*
X214240Y403173D01*
Y425995D01*
X217100Y432900D01*
Y436100D01*
G01X245500Y127800D02*
X244700Y127000D01*
X241000D01*
X237574Y130426D01*
Y140484D01*
X229470Y148588D01*
Y153330D01*
X227232Y155568D01*
Y164577D01*
X228702Y166047D01*
G01X244450Y178646D02*
X244224Y178420D01*
G02X243942Y178179I-1657J1653D01*
G02X241534Y177165I-3384J4669D01*
G02X241165Y177123I-577J3431D01*
G03X239755Y175620I96J-1503D01*
G01Y171985D01*
G03X240390Y170452I2168J0D01*
G01X240649Y170193D01*
G02X241537Y168049I-2144J-2144D01*
G01Y165376D01*
G03X241815Y164705I949J0D01*
G01X242638Y163882D01*
G02X242870Y163323I-559J-560D01*
G01Y162590D01*
G03X244100Y161360I1230J0D01*
G01X244610D01*
G02X246000Y159970I0J-1390D01*
G01Y159480D01*
G03X247580Y157900I1580J0D01*
G01X248200D01*
G02X248771Y157688I-1J-877D01*
G01X249325Y157134D01*
G03X250226Y156761I901J902D01*
G01X293292D01*
G03X296802Y158215I0J4964D01*
G01X306226Y167639D01*
G02X307674Y168239I1448J-1447D01*
G01X308200D01*
G03X309655Y169694I0J1455D01*
G01Y176753D01*
G03X308963Y178424I-2364J0D01*
G01X308152Y179235D01*
G01X250749Y184945D02*
Y183719D01*
G02X250409Y183379I-340J0D01*
G01X246441D01*
G02X245990Y183830I0J451D01*
G01Y186025D01*
G03X245525Y186490I-465J0D01*
G01X243507D01*
G03X242919Y185902I0J-588D01*
G01Y183803D01*
G02X242283Y183167I-636J0D01*
G01X239965D01*
G03X239500Y182702I0J-465D01*
G01Y180924D01*
G03X240177Y180247I677J0D01*
G01X254508D01*
G02X255488Y179267I0J-980D01*
G01Y179026D01*
G03X256294Y178220I806J0D01*
G01X256441D01*
G02X257167Y177494I0J-726D01*
G01Y175764D01*
G03X257507Y175424I340J0D01*
G01X258652D01*
G03X259011Y175783I0J359D01*
G01Y179016D01*
G03X258468Y179559I-543J0D01*
G01X257034D01*
G02X256593Y180000I0J441D01*
G01Y181179D01*
G02X257147Y181733I554J0D01*
G01X260557D01*
G02X261175Y181115I0J-618D01*
G01Y177682D01*
G03X261668Y177155I528J0D01*
G02X262034Y176765I-25J-390D01*
G01Y172169D01*
G03X262451Y171752I417J0D01*
G01X264159D01*
G03X264515Y172108I0J356D01*
G01Y174669D01*
G02X264846Y175000I331J0D01*
G01X267016D01*
G02X267346Y174670I0J-330D01*
G01Y172489D01*
G03X267840Y171995I494J0D01*
G01X269053D01*
G03X269586Y172528I0J533D01*
G01Y173135D01*
G02X270659Y174208I1073J0D01*
G01X271028D01*
G03X271905Y175085I0J877D01*
G01Y175502D01*
G02X272782Y176379I877J0D01*
G01X274587D01*
G02X275332Y175634I0J-745D01*
G01Y170407D01*
G03X275744Y169995I412J0D01*
G01X277202D01*
G03X277674Y170467I0J472D01*
G01Y173850D01*
G02X278014Y174190I340J0D01*
G01X281055D01*
G02X282258Y173692I0J-1702D01*
G01X282975Y172975D01*
G01X289254Y172792D02*
Y174206D01*
G03X288884Y174576I-370J0D01*
G01X284631D01*
G02X284383Y174671I0J371D01*
G02X284261Y174946I249J275D01*
G01Y175725D01*
G03X283891Y176095I-370J0D01*
G01X282300D01*
Y176100D01*
X281826D01*
G02X279863Y176913I0J2776D01*
G01X278295Y178481D01*
G03X277655Y178746I-640J-640D01*
G01X273960D01*
G02X273620Y179086I0J340D01*
G01Y180081D01*
G03X273250Y180451I-370J0D01*
G01X271831D01*
G03X271461Y180081I0J-370D01*
G01Y179818D01*
G02X271091Y179448I-370J0D01*
G01X270709D01*
G02X270403Y179575I0J433D01*
G01X268933Y181045D01*
G03X267375I-779J-779D01*
G01X266177Y179847D01*
G02X265653I-262J262D01*
G01X264614Y180886D01*
G02Y181410I262J262D01*
G01X266293Y183089D01*
G03Y183571I-241J241D01*
G01X264160Y185704D01*
G03X263854Y185831I-306J-306D01*
G01X259747D01*
G03X259407Y185491I0J-340D01*
G01Y183608D01*
G02X259067Y183268I-340J0D01*
G01X257761D01*
G02X257421Y183608I0J340D01*
G01Y186053D01*
G03X257081Y186393I-340J0D01*
G01X255759D01*
G03X255419Y186053I0J-340D01*
G01Y181865D01*
G02X255079Y181525I-340J0D01*
G01X252648D01*
G02X252308Y181865I0J340D01*
G01Y186104D01*
G03X251903Y186509I-405J0D01*
G01X249580D01*
G02X249210Y186879I0J370D01*
G01Y188679D01*
G03X249098Y188949I-381J0D01*
G01X248407Y189640D01*
G03X248144Y189749I-263J-263D01*
G01X246335D01*
G02X245965Y190119I0J370D01*
G01Y195320D01*
G03X245625Y195660I-340J0D01*
G01X239520D01*
G03X239180Y195320I0J-340D01*
G01Y193213D01*
G03X239520Y192873I340J0D01*
G01X242464D01*
G02X242809Y192528I0J-345D01*
G01Y190098D01*
G02X242365Y189654I-444J0D01*
G01X239522D01*
G03X239182Y189314I0J-340D01*
G01Y186851D01*
G03X239522Y186511I340J0D01*
G01X241380D01*
G03X242224Y186861I0J1193D01*
G01X243458Y188095D01*
X244450D01*
G01X235038Y229039D02*
X236600Y227477D01*
Y224600D01*
X236995Y224205D01*
X242305D01*
X242900Y224800D01*
Y233500D01*
X243453Y234053D01*
X244627D01*
X248174Y237600D01*
X249300D01*
G01X230000Y255700D02*
Y258190D01*
X227860Y260330D01*
Y265140D01*
X228420Y265700D01*
Y268209D01*
X230100Y269889D01*
Y280560D01*
X231540Y282000D01*
Y287740D01*
X229775Y289505D01*
Y300710D01*
X230565Y301500D01*
Y321309D01*
X232610Y323354D01*
Y327614D01*
X232024Y328200D01*
X228944D01*
X227815Y329329D01*
Y339625D01*
X228230Y340040D01*
G01X239298Y268800D02*
Y277392D01*
X238820Y277870D01*
Y284070D01*
X240190Y285440D01*
X245635D01*
X246370Y286175D01*
Y288630D01*
X245610Y289390D01*
X237000D01*
X236340Y290050D01*
Y291060D01*
X237000Y291720D01*
X243630D01*
X244290Y292380D01*
Y293390D01*
X243630Y294050D01*
X237026D01*
X236695Y294381D01*
Y296049D01*
X237026Y296380D01*
X243430D01*
X244090Y297040D01*
Y298050D01*
X243430Y298710D01*
X235290D01*
X234800Y299200D01*
Y300700D01*
X235140Y301040D01*
X242535D01*
X242865Y301370D01*
Y303236D01*
X238736Y307365D01*
X236105D01*
X234655Y308815D01*
Y319613D01*
X238542Y323500D01*
X239520D01*
X243330Y319690D01*
Y313920D01*
X242460Y313050D01*
X238521D01*
X236688Y311217D01*
G01X237700Y257387D02*
X238513Y258200D01*
X246201D01*
X258100Y270099D01*
X259599D01*
X264265Y274765D01*
Y281597D01*
X263700Y282162D01*
Y291636D01*
X262305Y293031D01*
Y304296D01*
X255425Y311176D01*
Y313424D01*
X257400Y315399D01*
Y325700D01*
X249700Y333400D01*
Y373200D01*
X248800Y374100D01*
Y385700D01*
G01X231689Y334896D02*
X231700Y334885D01*
Y333600D01*
X232300Y333000D01*
X237260D01*
X238855Y334595D01*
Y350435D01*
X239500Y351080D01*
X240970D01*
X241550Y350500D01*
Y333994D01*
X237845Y330289D01*
Y329355D01*
X238700Y328500D01*
Y325822D01*
X233125Y320247D01*
Y300439D01*
X232335Y299649D01*
Y290567D01*
X237220Y285682D01*
Y284672D01*
X236560Y284012D01*
X234760D01*
X234100Y283352D01*
Y280400D01*
X236220Y278280D01*
Y265392D01*
X238531Y263081D01*
G01X263102Y91725D02*
X262575Y91198D01*
X262560D01*
X262230Y90868D01*
Y78756D01*
X249475Y66001D01*
Y55812D01*
G01X292384Y172936D02*
X293377D01*
G02X293747Y172566I0J-370D01*
G01Y171694D01*
G03X294146Y171295I399J0D01*
G01X297364D01*
G02X297704Y170955I0J-340D01*
G01Y165912D01*
G02X297162Y165370I-542J0D01*
G01X295795D01*
G02X295455Y165710I0J340D01*
G01Y167835D01*
G03X295115Y168175I-340J0D01*
G01X292439D01*
G03X292099Y167835I0J-340D01*
G01Y165317D01*
G03X292439Y164977I340J0D01*
G01X293235D01*
G02X293786Y164426I0J-551D01*
G01Y162109D01*
G02X293234Y161557I-552J0D01*
G01X263775D01*
G02X263405Y161927I0J370D01*
G01Y165081D01*
G03X263035Y165451I-370J0D01*
G01X261635D01*
G03X261265Y165081I0J-370D01*
G01Y162401D01*
G02X260925Y162061I-340J0D01*
G01X259102D01*
G02X258762Y162401I0J340D01*
G01Y164031D01*
G03X258232Y164561I-530J0D01*
G01X256244D01*
G02X255537Y165268I0J707D01*
G01Y170292D01*
G03X255098Y170731I-439J0D01*
G01X253347D01*
G03X252367Y169751I0J-980D01*
G01Y165433D01*
G02X251458Y164524I-909J0D01*
G01X250530D01*
G02X249184Y165870I0J1346D01*
G01Y169628D01*
G03X248149Y170663I-1035J0D01*
G01X247969D01*
G02X247599Y171033I0J370D01*
G01Y172347D01*
G01Y178646D02*
X246723Y177770D01*
G03X246077Y176210I1561J-1560D01*
G01Y174970D01*
G02X244994Y173887I-1083J0D01*
G01X243771D01*
G03X242818Y172934I0J-953D01*
G01Y165822D01*
G03X244140Y164500I1322J0D01*
G01X244760D01*
G02X246030Y163230I0J-1270D01*
G01Y162580D01*
G03X247310Y161300I1280J0D01*
G01X248000D01*
G02X248683Y161017I0J-966D01*
G01X248800Y160900D01*
G02X249200Y159934I-966J-966D01*
G01Y159430D01*
G03X250431Y158199I1231J0D01*
G01X251988D01*
G03X252358Y158569I0J370D01*
G01Y160093D01*
G02X253635Y161370I1277J0D01*
G01X254465D01*
G02X255421Y160414I0J-956D01*
G01Y158569D01*
G03X255791Y158199I370J0D01*
G01X257105D01*
G03X258843Y158286I0J17397D01*
G01X260307Y158433D01*
G02X260676Y158451I365J-3686D01*
G01X292382D01*
G03X296078Y159982I0J5227D01*
G01X300417Y164321D01*
G03X300555Y164654I-333J333D01*
G01Y165676D01*
G02X301711Y166832I1156J0D01*
G01X303383D01*
G03X303753Y167202I0J370D01*
G01Y168782D01*
G03X303383Y169152I-370J0D01*
G01X301453D01*
G02X301113Y169492I0J340D01*
G01Y171023D01*
G02X301453Y171363I340J0D01*
G01X306209D01*
G03X306579Y171733I0J370D01*
G01Y173334D01*
G02X306688Y173597I372J0D01*
G01X308152Y175061D01*
Y176085D01*
G01X292260Y179235D02*
X293291Y178806D01*
G02X294388Y178127I-1555J-3737D01*
G03X295527Y177702I1138J1312D01*
G01X296587D01*
G02X297080Y177209I0J-493D01*
G01Y176232D01*
G03X297515Y175797I435J0D01*
G01X298542D01*
G03X298977Y176232I0J435D01*
G01Y178170D01*
G02X299307Y178500I330J0D01*
G01X300667D01*
G02X300997Y178170I0J-330D01*
G01Y174582D01*
G02X300627Y174212I-370J0D01*
G01X297421D01*
G03X297051Y173842I0J-370D01*
G01Y172722D01*
G03X297421Y172352I370J0D01*
G01X298370D01*
G02X299337Y171385I0J-967D01*
G01Y166389D01*
G02X299220Y165709I-2023J-2D01*
G02X299037Y165421I-729J261D01*
G01X294923Y161307D01*
G02X292561Y160075I-3138J3136D01*
G02X291641Y159995I-915J5189D01*
G01X259821D01*
G02X258585Y160507I0J1748D01*
G01X258020Y161072D01*
G03X257445Y161310I-575J-576D01*
G01X256449D01*
G02X255404Y162355I0J1045D01*
G01Y163403D01*
G03X254396Y164411I-1008J0D01*
G01X253679D01*
G03X252400Y163132I0J-1279D01*
G01Y162266D01*
G02X252176Y161516I-1366J0D01*
G02X251776Y161300I-400J263D01*
G01X250230D01*
G02X249240Y162290I0J990D01*
G01Y163238D01*
G03X248800Y164300I-1502J0D01*
G03X248317Y164500I-483J-483D01*
G01X247083D01*
G02X246600Y164700I0J683D01*
G02X246053Y166021I1321J1321D01*
G01Y170307D01*
G03X245633Y170727I-420J0D01*
G01X244820D01*
G02X244450Y171097I0J370D01*
G01Y172347D01*
G01X295410Y172936D02*
Y174127D01*
G03X295040Y174497I-370J0D01*
G01X291084D01*
G03X290744Y174157I0J-340D01*
G01Y166332D01*
G02X290404Y165992I-340J0D01*
G01X288919D01*
G02X288579Y166332I0J340D01*
G01Y170737D01*
G03X287904Y171412I-675J0D01*
G01X282506D01*
G03X281861Y170767I0J-645D01*
G01Y170028D01*
G02X281356Y169523I-505J0D01*
G01X279666D01*
G03X279326Y169183I0J-340D01*
G01Y168640D01*
G02X278803Y168117I-523J0D01*
G01X274206D01*
G02X273752Y168571I0J454D01*
G01Y171960D01*
G03X273412Y172300I-340J0D01*
G01X271922D01*
G03X271582Y171960I0J-340D01*
G01Y168763D01*
G02X271207Y168388I-375J0D01*
G01X269810D01*
G02X269440Y168758I0J370D01*
G01Y170160D01*
G03X269100Y170500I-340J0D01*
G01X267630D01*
G03X267290Y170160I0J-340D01*
G01Y168765D01*
G02X266920Y168395I-370J0D01*
G01X265483D01*
G02X265113Y168765I0J370D01*
G01Y169560D01*
G03X264773Y169900I-340J0D01*
G01X263299D01*
G03X262959Y169560I0J-340D01*
G01Y168757D01*
G02X262464Y168262I-495J0D01*
G01X261285D01*
G02X260790Y168757I0J495D01*
G01Y169928D01*
G03X260420Y170298I-370J0D01*
G01X258969D01*
G02X258599Y170668I0J370D01*
G01Y173492D01*
G03X258229Y173862I-370J0D01*
G01X255797D01*
G02X255427Y174232I0J370D01*
G01Y176676D01*
G03X255057Y177046I-370J0D01*
G01X252623D01*
G03X252253Y176676I0J-370D01*
G01Y171807D01*
G02X251259Y170813I-994J0D01*
G01X250029D01*
G02X249264Y171578I0J765D01*
G01Y178267D01*
G02X249643Y178646I379J0D01*
G01X250749D01*
G01X247599Y191244D02*
X248600D01*
X249873Y189971D01*
G03X250587Y189675I714J713D01*
G01X251215D01*
G02X252359Y188531I0J-1144D01*
G01Y187673D01*
G03X252773Y187259I414J0D01*
G01X261983D01*
G03X262323Y187599I0J340D01*
G01Y189482D01*
G02X262663Y189822I340J0D01*
G01X264128D01*
G02X265622Y189203I0J-2112D01*
G01X266000Y188825D01*
G02X266187Y188388I-10014J-4544D01*
G01X266288Y188134D01*
G02X266308Y188060I-337J-131D01*
G03X266514Y187660I723J119D01*
G01X267019Y187155D01*
G03X267328Y186950I668J671D01*
G02X267759Y186771I-63171J-152714D01*
G02X268067Y186563I-373J-884D01*
G01X270710Y183920D01*
G03X271686Y183516I976J977D01*
G01X274356D01*
G02X274619Y183407I0J-372D01*
G01X276100Y181926D01*
G03X276364Y181817I264J265D01*
G01X278720D01*
G02X279036Y181708I0J-512D01*
G01X282431Y179056D01*
G03X282746Y178947I316J403D01*
G01X287272D01*
G03X287612Y179287I0J340D01*
G01Y180388D01*
G02X287982Y180758I370J0D01*
G01X289411D01*
G03X289959Y180985I0J775D01*
G01X291192Y182218D01*
G02X291544Y182364I352J-351D01*
G01X306259D01*
G03X306703Y182808I0J444D01*
G01Y183539D01*
G02X307043Y183879I340J0D01*
G01X312186D01*
G03X312649Y184342I0J463D01*
G01Y188076D01*
G02X313019Y188446I370J0D01*
G01X317702D01*
G02X318200Y187948I0J-498D01*
G01Y186643D01*
G02X317860Y186303I-340J0D01*
G01X316184D01*
G03X315844Y185963I0J-340D01*
G01Y184503D01*
G03X316184Y184163I340J0D01*
G01X317657D01*
G02X317997Y183823I0J-340D01*
G01Y171736D01*
G02X317550Y171289I-447J0D01*
G01X314930D01*
G01X292404Y185534D02*
X293264D01*
G03X293753Y186023I0J489D01*
G01Y186842D01*
G03X293165Y187430I-588J0D01*
G01X284889D01*
G03X284549Y187090I0J-340D01*
G01Y184022D01*
G02X284209Y183682I-340J0D01*
G01X282913D01*
G02X282573Y184022I0J340D01*
G01Y188495D01*
G03X282233Y188835I-340J0D01*
G01X280763D01*
G03X280423Y188495I0J-340D01*
G01Y185712D01*
G02X280053Y185342I-370J0D01*
G01X277839D01*
G02X277501Y185482I0J478D01*
G01X276146Y186837D01*
G02Y187319I241J241D01*
G01X278661Y189834D01*
G03Y190690I-428J428D01*
G01X277727Y191624D01*
G03X277245I-241J-241D01*
G01X274710Y189089D01*
G02X274196I-257J257D01*
G01X273176Y190109D01*
G02Y190591I241J241D01*
G01X274679Y192094D01*
G03Y192687I-297J296D01*
G01X274255Y193111D01*
G03X273570Y193397I-685J-677D01*
G01X270915D01*
G03X270360Y192842I0J-555D01*
G01Y191880D01*
G02X270020Y191540I-340J0D01*
G01X268469D01*
G02X268129Y191880I0J340D01*
G01Y193084D01*
G03X268078Y193265I-341J2D01*
G01Y193266D01*
G03X267575Y193545I-503J-314D01*
G01X261484D01*
G02X261144Y193885I0J340D01*
G01Y195356D01*
G02X261484Y195696I340J0D01*
G01X266781D01*
G03X267121Y196036I0J340D01*
G01Y197513D01*
G03X266781Y197853I-340J0D01*
G01X260954D01*
G03X260118Y197507I0J-1183D01*
G01X258849Y196238D01*
G03X258670Y195806I432J-432D01*
G01Y193100D01*
G02X258330Y192760I-340J0D01*
G01X256899D01*
G02X256559Y193100I0J340D01*
G01Y195877D01*
G03X256189Y196247I-370J0D01*
G01X254982D01*
G03X254612Y195877I0J-370D01*
G01Y193067D01*
G02X254272Y192727I-340J0D01*
G01X252840D01*
G02X252500Y193067I0J340D01*
G01Y197166D01*
G02X252840Y197506I340J0D01*
G01X253898D01*
G01X308008Y188540D02*
X305510D01*
G02X305092Y188958I0J418D01*
G01Y191844D01*
G03X304752Y192184I-340J0D01*
G01X301358D01*
G03X300854Y191680I0J-504D01*
G01Y190694D01*
G03X301194Y190354I340J0D01*
G01X303004D01*
G02X303344Y190014I0J-340D01*
G01Y187179D01*
G03X304064Y186459I720J0D01*
G01X305425D01*
G02X306145Y185739I0J-720D01*
G01Y185339D01*
G02X305425Y184619I-720J0D01*
G01X303818D01*
G03X303344Y184144I1J-475D01*
G01Y183670D01*
G02X303004Y183330I-340J0D01*
G01X301507D01*
G02X301137Y183700I0J370D01*
G01Y188296D01*
G03X300797Y188636I-340J0D01*
G01X299350D01*
G03X299010Y188296I0J-340D01*
G01Y183774D01*
G02X298640Y183404I-370J0D01*
G01X297400D01*
G02X297040Y183684I-1J370D01*
G03X296681Y183965I-359J-89D01*
G01X287993D01*
G03X287653Y183625I0J-340D01*
G01Y182214D01*
G02X286784Y180915I-1405J0D01*
G02X286360Y180831I-424J1030D01*
G01X285622D01*
G02X285282Y180861I-2J1917D01*
G02X284207Y181262I571J3172D01*
G03X283347Y181616I-1644J-2772D01*
G02X282130Y182067I1482J5868D01*
G02X281854Y182267I474J944D01*
G01X280792Y183329D01*
G03X279828Y183914I-1677J-1677D01*
G03X279491Y183965I-335J-1072D01*
G01X277232D01*
G02X276991Y184065I0J340D01*
G01X274509Y186547D01*
G03X273984I-263J-262D01*
G01X273211Y185774D01*
G02X272687I-262J262D01*
G01X271685Y186776D01*
G02Y187301I263J262D01*
G01X272607Y188223D01*
G03Y188747I-262J262D01*
G01X271304Y190050D01*
G03X270998Y190177I-306J-306D01*
G01X268008D01*
G02X267506Y190385I0J709D01*
G01X266484Y191407D01*
G03X266220Y191622I-1155J-1148D01*
G03X264979Y191989I-1239J-1910D01*
G01X260568D01*
G03X260228Y191649I0J-340D01*
G01Y190063D01*
G02X259888Y189723I-340J0D01*
G01X253389D01*
G02X252374Y190738I0J1015D01*
G01Y191009D01*
G03X251593Y192465I-1748J0D01*
G01X251456Y192556D01*
G03X251149Y192704I-694J-1047D01*
G02X250749Y193256I181J552D01*
G01Y197506D01*
G01X308008Y198133D02*
Y197219D01*
G02X307161Y196372I-847J0D01*
G01X306604D01*
G02X305268Y197708I0J1336D01*
G01Y199663D01*
G03X303288I-990J0D01*
G01Y198010D01*
G02X302332Y197054I-956J0D01*
G01X302264D01*
G02X301308Y198010I0J956D01*
G01Y198860D01*
G03X300352Y199816I-956J0D01*
G01X300284D01*
G03X299328Y198860I0J-956D01*
G01Y196030D01*
G02X298398Y195100I-930J0D01*
G01X298023D01*
G03X297249Y194326I0J-774D01*
G01Y191039D01*
G02X296021Y189811I-1228J0D01*
G01X287864D01*
G02X286929Y190746I0J935D01*
G01Y190858D01*
G03X286074Y191713I-855J0D01*
G01X281673D01*
G02X281432Y191813I0J340D01*
G01X279640Y193605D01*
G03X277550Y194471I-2090J-2089D01*
G01X277516D01*
G02X277176Y194811I0J340D01*
G01Y195661D01*
G03X276685Y196152I-491J0D01*
G01X270356D01*
G02X270016Y196492I0J340D01*
G01Y200291D01*
G03X269676Y200631I-340J0D01*
G01X259908D01*
G03X258642Y200107I0J-1792D01*
G01X258151Y199616D01*
G02X256948Y199118I-1203J1204D01*
G01X250875D01*
G03X249704Y198633I0J-1656D01*
G01X249656Y198585D01*
G03X249171Y197414I1171J-1171D01*
G01Y195842D01*
G02X248831Y195502I-340J0D01*
G01X247895D01*
G03X247555Y195162I0J-340D01*
G01Y194482D01*
G03X247895Y194142I340J0D01*
G01X248831D01*
G02X249171Y193802I0J-340D01*
G01Y193448D01*
G03X249614Y192379I1511J0D01*
G01X250749Y191244D01*
G01Y203805D02*
X250747D01*
Y202435D01*
G02X250407Y202095I-340J0D01*
G01X249585D01*
G02X249229Y202451I0J356D01*
G01Y204383D01*
G03X248276Y205336I-953J0D01*
G01X245444D01*
G02X245104Y205676I0J340D01*
G01Y207919D01*
G02X245746Y208561I642J0D01*
G01X248778D01*
G03X249229Y209012I0J451D01*
G01Y211389D01*
G02X249610Y211770I381J0D01*
G01X255676D01*
G02X256041Y211405I0J-365D01*
G01Y208523D01*
G02X255701Y208183I-340J0D01*
G01X254833D01*
G02X254493Y208523I0J340D01*
G01Y210667D01*
G03X254153Y211007I-340J0D01*
G01X252730D01*
G03X252390Y210667I0J-340D01*
G01Y208827D01*
G02X251994Y208431I-396J0D01*
G01X250200D01*
G03X249870Y208348I-2J-690D01*
G03X249270Y207337I550J-1010D01*
G01Y206186D01*
G03X249992Y205464I722J0D01*
G01X252050D01*
G02X252390Y205124I0J-340D01*
G01Y202554D01*
G03X252760Y202184I370J0D01*
G01X254241D01*
G03X254581Y202524I0J340D01*
G01Y205452D01*
G02X254921Y205792I340J0D01*
G01X255968D01*
G02X256308Y205452I0J-340D01*
G01Y203782D01*
G03X256648Y203442I340J0D01*
G01X271414D01*
G02X272494Y203122I1J-1980D01*
G01X272950Y202825D01*
G03X272968Y202814I193J296D01*
G01X273094Y202742D01*
G03X273487Y202638I393J691D01*
G01X277034D01*
G02X277374Y202298I0J-340D01*
G01Y200076D01*
G03X277714Y199736I340J0D01*
G01X281928D01*
G03X282268Y200076I0J340D01*
G01Y201697D01*
G02X282674Y202103I406J0D01*
G01X284078D01*
G02X284484Y201697I0J-406D01*
G01Y199996D01*
G03X284824Y199656I340J0D01*
G01X287313D01*
G02X287653Y199316I0J-340D01*
G01Y193637D01*
G03X287993Y193297I340J0D01*
G01X288914D01*
G03X289254Y193637I0J340D01*
G01Y194839D01*
G01X247599Y200655D02*
Y201508D01*
G03X246840Y202267I-759J0D01*
G01X244521D01*
G02X242993Y203571I0J1547D01*
G02X242983Y203912I1307J209D01*
G02X245537Y210146I11781J-1186D01*
G02X245765Y210399I2449J-1978D01*
G01X246956Y211590D01*
G02X247262Y211717I306J-306D01*
G01X247585D01*
G03X249211Y213343I0J1626D01*
G01Y214024D01*
G02X249932Y214745I721J0D01*
G01X259015D01*
G03X259355Y215085I0J340D01*
G01Y216169D01*
G02X259559Y216641I648J0D01*
G02X259876Y216766I316J-337D01*
G01X271858D01*
G02X272175Y216641I1J-462D01*
G02X272379Y216169I-444J-472D01*
G01Y214705D01*
G03X272719Y214365I340J0D01*
G01X274179D01*
G03X274519Y214705I0J340D01*
G01Y216169D01*
G02X275210Y216860I691J0D01*
G01X282909D01*
G02X284579Y215190I0J-1670D01*
G01Y212674D01*
G03X285124Y212129I545J0D01*
G01X296045D01*
G02X297082Y211092I0J-1037D01*
G01Y208621D01*
G03X297422Y208281I340J0D01*
G01X300104D01*
G02X300444Y207941I0J-340D01*
G01Y206481D01*
G02X300104Y206141I-340J0D01*
G01X297422D01*
G03X297082Y205801I0J-340D01*
G01Y204047D01*
G03X297422Y203707I340J0D01*
G01X301348D01*
G02X301688Y203367I0J-340D01*
G01Y201674D01*
G02X301348Y201334I-340J0D01*
G01X299667D01*
G01X308008Y191690D02*
X308228Y191910D01*
G03X309633Y195301I-3390J3391D01*
G01Y197918D01*
G03X309133Y199124I-1706J-1D01*
G01X308750Y199507D01*
G03X308462Y199740I-1226J-1221D01*
G03X307312Y200320I-3367J-5245D01*
G02X305120Y201738I2214J5826D01*
G01X304237Y202621D01*
G02X303251Y204061I3358J3357D01*
G01X300050Y211312D01*
G03X299832Y211568I-539J-238D01*
G01X297807Y212888D01*
G03X296379Y213559I-3123J-4791D01*
G02X294777Y214349I1698J5462D01*
G02X294511Y214560I1979J2768D01*
G03X294263Y214746I-1497J-1737D01*
G03X292041Y215406I-2222J-3410D01*
G02X290654Y215638I0J4260D01*
G02X288902Y216281I15735J45583D01*
G01X283973Y218200D01*
G03X283119Y218360I-853J-2194D01*
G01X259960D01*
G03X258917Y218021I0J-1773D01*
G01X258916Y218020D01*
G02X258715Y217955I-200J277D01*
G01X250119D01*
G03X249796Y217847I-1J-533D01*
G03X249255Y216755I832J-1092D01*
G01Y216206D01*
G02X247937Y214888I-1318J0D01*
G01X247245D01*
G03X245981Y213624I0J-1264D01*
G01Y212611D01*
G02X245632Y211769I-1190J0D01*
G03X243352Y208498I8487J-8346D01*
G01X242330Y206285D01*
G03X242240Y205958I940J-435D01*
G01X242036Y204002D01*
G03X242042Y203661I1357J-147D01*
G03X242640Y201491I9031J1321D01*
G01X242787Y201136D01*
G02X242933Y200514I-1830J-758D01*
G03X244476Y199080I1543J113D01*
G01X247603D01*
G03X248508Y199455I0J1279D01*
G01X248926Y199873D01*
X250749Y200655D01*
G01X289254Y191690D02*
X287714D01*
G02X287374Y192030I0J340D01*
G01Y192291D01*
G03X286569Y193083I-806J-14D01*
G01X285493Y193084D01*
X282739D01*
G02X282329Y193494I0J410D01*
G01Y195296D01*
G02X282669Y195636I340J0D01*
G01X284281D01*
G03X284621Y195976I0J340D01*
G01Y197989D01*
G03X284281Y198329I-340J0D01*
G01X280830D01*
G03X280490Y197989I0J-340D01*
G01Y196580D01*
G02X280150Y196240I-340J0D01*
G01X278675D01*
G02X278335Y196580I0J340D01*
G01Y197986D01*
G03X277995Y198326I-340J0D01*
G01X276318D01*
G02X275978Y198666I0J340D01*
G01Y200923D01*
G03X275638Y201263I-340J0D01*
G01X274178D01*
G03X273838Y200923I0J-340D01*
G01Y197918D01*
G02X273498Y197578I-340J0D01*
G01X271981D01*
G02X271641Y197918I0J340D01*
G01Y201704D01*
G03X271301Y202044I-340J0D01*
G01X258318D01*
G02X257965Y202168I1J568D01*
G01X257705Y202374D01*
G03X257352Y202497I-353J-445D01*
G01X255760D01*
G03X255420Y202157I0J-340D01*
G01Y200995D01*
G03X255760Y200655I340J0D01*
G01X257048D01*
G01X242940Y268500D02*
Y268626D01*
X244311Y269997D01*
X246140Y274413D01*
Y274496D01*
X246208D01*
X249630Y277918D01*
Y288848D01*
X251070Y290288D01*
Y300700D01*
X254186Y303816D01*
Y306714D01*
X251070Y309830D01*
Y314329D01*
X248999Y316400D01*
X247923D01*
G01X242087Y271427D02*
Y275496D01*
X248300Y281709D01*
Y289399D01*
X249664Y290763D01*
Y301264D01*
X251400Y303000D01*
Y307230D01*
X244900Y313730D01*
Y322298D01*
X246650Y326522D01*
Y371250D01*
X245170Y372730D01*
X243700D01*
G01X253320Y323327D02*
Y315520D01*
X252400Y314600D01*
Y310400D01*
X257100Y305700D01*
Y299500D01*
X254554Y296954D01*
Y283353D01*
X253200Y281999D01*
Y279607D01*
X247470Y273877D01*
Y269990D01*
G01X261500Y290440D02*
X260265Y291675D01*
Y304435D01*
X254000Y310700D01*
Y314100D01*
X255510Y315610D01*
Y325689D01*
X248370Y332829D01*
Y333131D01*
X248285Y333216D01*
Y372415D01*
X244790Y375910D01*
G01X289110Y163487D02*
Y164460D01*
G03X288770Y164800I-340J0D01*
G01X287398D01*
G02X287012Y165186I0J386D01*
G01Y169904D01*
G03X286642Y170274I-370J0D01*
G01X284333D01*
G03X283993Y169934I0J-340D01*
G01Y167030D01*
G03X284236Y166704I340J0D01*
G02X284478Y166378I-99J-326D01*
G01Y163264D01*
G02X284138Y162924I-340J0D01*
G01X282211D01*
G02X281871Y163264I0J340D01*
G01Y166642D01*
G03X281531Y166982I-340J0D01*
G01X280047D01*
G03X279707Y166642I0J-340D01*
G01Y163320D01*
G02X279339Y162952I-368J0D01*
G01X277699D01*
G02X277359Y163292I0J340D01*
G01Y166392D01*
G03X277019Y166732I-340J0D01*
G01X275544D01*
G03X275204Y166392I0J-340D01*
G01Y163450D01*
G02X274834Y163080I-370J0D01*
G01X273431D01*
G02X273061Y163450I0J370D01*
G01Y166543D01*
G03X272691Y166913I-370J0D01*
G01X271288D01*
G03X270918Y166543I0J-370D01*
G01Y163585D01*
G02X270413Y163080I-505J0D01*
G01X267444D01*
G02X267074Y163450I0J370D01*
G01Y166485D01*
G03X266704Y166855I-370J0D01*
G01X257582D01*
G02X257348Y166952I0J331D01*
G01X257142Y167158D01*
G02X257045Y167392I234J234D01*
G01Y172034D01*
X257048Y172347D01*
G01X264118Y188095D02*
X264762Y187451D01*
G02X264867Y187250I-269J-269D01*
G03X264970Y187054I364J66D01*
G01X269704Y182320D01*
G03X270360Y182048I656J655D01*
G01X273350D01*
G02X274166Y181710I0J-1154D01*
G01X275499Y180377D01*
G03X276122Y180119I623J623D01*
G01X278444D01*
G02X278750Y179992I0J-433D01*
G01X280127Y178615D01*
G03X282618Y177583I2492J2493D01*
G01X289518D01*
G03X290010Y177787I0J696D01*
G01X290605Y178382D01*
G03X290714Y178645I-263J263D01*
G01Y179697D01*
G02X290823Y179960I372J0D01*
G01X291398Y180535D01*
G02X291934Y180757I536J-536D01*
G01X303041D01*
G02X303411Y180387I0J-370D01*
G01Y178025D01*
G03X303751Y177685I340J0D01*
G01X306326D01*
G03X306666Y178025I0J340D01*
G01Y180387D01*
G02X307158Y180879I492J0D01*
G01X311892D01*
G03X312387Y181084I0J700D01*
G01X313568Y182265D01*
G02X313831Y182374I263J-263D01*
G01X316076D01*
G02X316446Y182004I0J-370D01*
G01Y179510D01*
G02X316076Y179140I-370J0D01*
G01X313148D01*
G03X312571Y178563I0J-577D01*
G01Y176513D01*
G03X313148Y175936I577J0D01*
G01X316093D01*
G02X316463Y175566I0J-370D01*
G01Y173261D01*
G02X316093Y172891I-370J0D01*
G01X311528D01*
G03X311158Y172521I0J-370D01*
G01Y169643D01*
G01X257048Y197506D02*
X257939D01*
G03X258245Y197633I0J433D01*
G01X259238Y198626D01*
G02X260795Y199271I1557J-1558D01*
G01X268167D01*
G02X268507Y198931I0J-340D01*
G01Y195100D01*
G03X268847Y194760I340J0D01*
G01X275386D01*
G02X275885Y194261I0J-499D01*
G01Y193438D01*
G03X276225Y193098I340J0D01*
G01X277494D01*
G02X278718Y192591I0J-1731D01*
G01X280864Y190445D01*
G03X281105Y190345I241J240D01*
G01X283567D01*
G02X283937Y189975I0J-370D01*
G01Y188960D01*
G03X284320Y188577I383J0D01*
G01X296836D01*
G03X298400Y190141I0J1564D01*
G01Y193098D01*
G02X298902Y193600I502J0D01*
G01X302898D01*
G03X303424Y194126I0J526D01*
G01Y194792D01*
G02X303887Y195255I463J0D01*
G01X306027D01*
G02X306490Y194792I0J-463D01*
G01Y190854D01*
G03X307259Y190085I769J0D01*
G01X315441D01*
G03X315811Y190455I0J370D01*
G01Y202360D01*
G03X315471Y202700I-340J0D01*
G01X313010D01*
G03X312670Y202360I0J-340D01*
G01Y192060D01*
G02X312300Y191690I-370J0D01*
G01X311158D01*
G01X292404D02*
X295583D01*
G03X295923Y192030I0J340D01*
G01Y192841D01*
G03X295583Y193181I-340J0D01*
G01X291204D01*
G02X290864Y193521I0J340D01*
G01Y202404D01*
G03X290524Y202744I-340J0D01*
G01X285962D01*
G02X284531Y204175I0J1431D01*
G01Y204827D01*
G03X284150Y205208I-381J0D01*
G01X281231D01*
G03X280891Y204868I0J-340D01*
G01Y201446D01*
G02X280551Y201106I-340J0D01*
G01X279086D01*
G02X278746Y201446I0J340D01*
G01Y203677D01*
G03X278406Y204017I-340J0D01*
G01X273900D01*
G02X273118Y204431I0J946D01*
G03X272332Y204845I-786J-539D01*
G01X258906D01*
G02X258566Y205185I0J340D01*
G01Y209205D01*
G02X259016Y209655I450J0D01*
G01X260936D01*
G03X261276Y209995I0J340D01*
G01Y212645D01*
G03X260936Y212985I-340J0D01*
G01X259152D01*
G03X258812Y212645I0J-340D01*
G01Y212086D01*
G02X258472Y211746I-340J0D01*
G01X257412D01*
G03X257055Y211389I0J-357D01*
G01Y206955D01*
X257048D01*
G01X264265Y315817D02*
X265502Y314580D01*
X268100Y308307D01*
Y273462D01*
X264700Y270062D01*
Y266445D01*
X265065Y266080D01*
Y260365D01*
X259572Y254872D01*
X258475D01*
G01X257900Y312100D02*
X263835Y306165D01*
Y293665D01*
X265800Y291700D01*
Y274015D01*
X260365Y268580D01*
Y266336D01*
X261601Y265100D01*
X262700D01*
G01X286000Y47000D02*
Y53442D01*
X281696Y57746D01*
Y68638D01*
X311269Y98211D01*
Y134669D01*
X320325Y143725D01*
Y146407D01*
X317881Y148851D01*
Y152061D01*
X321091Y155271D01*
Y193065D01*
X323973Y195947D01*
Y216358D01*
X322823Y217508D01*
X318935D01*
X317929Y216502D01*
X303987D01*
X299138Y221351D01*
Y244513D01*
G54D18*
G01X292404Y194983D02*
Y195003D01*
X293107Y195706D01*
G03X293284Y196069I-936J681D01*
G01X293390Y196437D01*
G02X293845Y197330I2535J-729D01*
G03X294500Y199230I-2434J1902D01*
G01Y202802D01*
G03X294147Y203653I-1202J0D01*
G01X294116Y203684D01*
G03X293303Y204021I-813J-812D01*
G01X292529D01*
G02X291716Y204358I0J1149D01*
G01X291669Y204405D01*
G02X291332Y205218I812J813D01*
G01Y205842D01*
G03X290890Y206910I-1511J0D01*
G01X290865Y206935D01*
G03X289743Y207400I-1122J-1121D01*
G01X289235D01*
G03X288032Y206902I0J-1702D01*
G01X287647Y206517D01*
G02X286834Y206180I-813J812D01*
G01X286766D01*
G02X285953Y206517I0J1149D01*
G01X285568Y206902D01*
G03X284365Y207400I-1203J-1204D01*
G01X282660D01*
G02X280660Y209400I0J2000D01*
G01Y212351D01*
G03X280457Y212837I-685J-1D01*
G03X279971Y213040I-487J-482D01*
G01X279292D01*
G03X278460Y212208I0J-832D01*
G01Y208478D01*
G02X276182Y206200I-2278J0D01*
G01X275352D01*
G02X273816Y206836I0J2173D01*
G01X273815Y206837D01*
G02X272900Y209046I2209J2209D01*
G01Y209911D01*
G03X272800Y210152I-340J0D01*
G01X272652Y210300D01*
G03X272411Y210400I-241J-240D01*
G01X271735D01*
G03X270532Y209902I0J-1702D01*
G01X270147Y209517D01*
G02X269334Y209180I-813J812D01*
G01X269266D01*
G02X268453Y209517I0J1149D01*
G01X268031Y209939D01*
G03X266919Y210400I-1112J-1111D01*
G01X266667D01*
G03X265869Y210069I1J-1129D01*
G01X265681Y209880D01*
G03X265578Y209765I1104J-1092D01*
G03X265469Y209614I1202J-983D01*
G03X265205Y208987I1753J-1107D01*
G03X265165Y208655I1392J-336D01*
G01X265166Y208340D01*
X265160Y208325D01*
Y207929D01*
X265189Y207749D01*
G03X265219Y207653I336J52D01*
G01X265299Y207490D01*
G03X265685Y207250I386J190D01*
G01X266068D01*
X266080Y207262D01*
G01X295410Y194839D02*
X295229Y195020D01*
G02X294983Y195967I679J682D01*
G01X294986Y195976D01*
Y195978D01*
G02X295154Y196309I940J-269D01*
G03X296160Y199229I-3743J2923D01*
G01Y202802D01*
G03X295321Y204827I-2863J0D01*
G01X292039Y208109D01*
G03X289743Y209060I-2296J-2296D01*
G01X285070D01*
G02Y209056I-141J-2D01*
G03X284929Y209060I-127J-1997D01*
G01X282660D01*
G02X282320Y209400I0J340D01*
G01Y212352D01*
G03X281636Y214006I-2345J-1D01*
G03X279972Y214700I-1665J-1651D01*
G01X279292D01*
G03X276800Y212208I0J-2492D01*
G01Y208478D01*
G02X276182Y207860I-618J0D01*
G01X275352D01*
G02X274990Y208010I0J512D01*
G01X274989Y208011D01*
G02X274560Y209046I1034J1035D01*
G01Y209911D01*
G03X273974Y211327I-2001J1D01*
G01X273827Y211474D01*
G03X272411Y212060I-1415J-1415D01*
G01X266666D01*
G03X264695Y211243I1J-2789D01*
G01X264506Y211054D01*
G03X264290Y210815I2273J-2272D01*
G03X264065Y210502I2492J-2029D01*
G03X263589Y209372I3157J-1995D01*
G03X263505Y208654I3008J-716D01*
G01X263441Y208491D01*
G02X263385Y208366I-6843J2991D01*
G01X262577Y207280D01*
X262580Y207262D01*
G01X451000Y-323400D02*
X447170D01*
X446830Y-323060D01*
Y-313018D01*
X445178Y-311366D01*
X418610D01*
X417930Y-310686D01*
Y-307206D01*
X418610Y-306526D01*
X474078D01*
X475730Y-304874D01*
Y-300018D01*
X474078Y-298366D01*
X418450D01*
X417770Y-297686D01*
Y-294206D01*
X418450Y-293526D01*
X474078D01*
X475730Y-291874D01*
Y-287018D01*
X474078Y-285366D01*
X417350D01*
X416670Y-284686D01*
Y-281206D01*
X417350Y-280526D01*
X474078D01*
X475730Y-278874D01*
Y-274018D01*
X474078Y-272366D01*
X417430D01*
X416750Y-271686D01*
Y-268206D01*
X417430Y-267526D01*
X474078D01*
X475730Y-265874D01*
Y-261018D01*
X474078Y-259366D01*
X417510D01*
X416830Y-258686D01*
Y-255206D01*
X417510Y-254526D01*
X445178D01*
X446830Y-252874D01*
Y-245340D01*
X447170Y-245000D01*
X451000D01*
G01X441000Y-323400D02*
X444830D01*
X445170Y-323060D01*
Y-313706D01*
X444490Y-313026D01*
X417922D01*
X416270Y-311374D01*
Y-306518D01*
X417922Y-304866D01*
X473390D01*
X474070Y-304186D01*
Y-300706D01*
X473390Y-300026D01*
X417762D01*
X416110Y-298374D01*
Y-293518D01*
X417762Y-291866D01*
X473390D01*
X474070Y-291186D01*
Y-287706D01*
X473390Y-287026D01*
X416662D01*
X415010Y-285374D01*
Y-280518D01*
X416662Y-278866D01*
X473390D01*
X474070Y-278186D01*
Y-274706D01*
X473390Y-274026D01*
X416742D01*
X415090Y-272374D01*
Y-267518D01*
X416742Y-265866D01*
X473390D01*
X474070Y-265186D01*
Y-261706D01*
X473390Y-261026D01*
X416822D01*
X415170Y-259374D01*
Y-254518D01*
X416822Y-252866D01*
X444490D01*
X445170Y-252186D01*
Y-245340D01*
X444830Y-245000D01*
X441000D01*
G54D19*
G01X92801Y452793D02*
X93880Y451714D01*
Y450150D01*
X93477Y449177D01*
X89588Y445289D01*
X85752Y443700D01*
X78290D01*
X76600Y444400D01*
X40170D01*
X13819Y433484D01*
X8715Y428380D01*
X6400Y422790D01*
Y350341D01*
X9894Y341906D01*
X14934Y336866D01*
X16100Y334051D01*
Y319900D01*
X7253Y311053D01*
Y125229D01*
X7877Y123723D01*
X35220Y96380D01*
X37180Y91648D01*
Y44147D01*
X39628Y38237D01*
X43289Y34576D01*
X54943Y29749D01*
X189607D01*
X200441Y31904D01*
X205005Y34344D01*
X232702Y54885D01*
X234133Y56719D01*
X235294Y59522D01*
X237820Y72221D01*
X257623Y92024D01*
Y105009D01*
X258713Y106099D01*
G01X96301Y452793D02*
X95200Y451692D01*
Y449887D01*
X94596Y448429D01*
X90336Y444170D01*
X86015Y442380D01*
X78027D01*
X76337Y443080D01*
X40433D01*
X14567Y432365D01*
X9834Y427632D01*
X7720Y422527D01*
Y350604D01*
X11013Y342654D01*
X16053Y337614D01*
X17420Y334314D01*
Y319353D01*
X8573Y310506D01*
Y125492D01*
X8996Y124471D01*
X36339Y97128D01*
X38500Y91911D01*
Y44410D01*
X40747Y38985D01*
X44037Y35695D01*
X55206Y31069D01*
X189476D01*
X199991Y33161D01*
X204296Y35463D01*
X212409Y41480D01*
X212586Y42670D01*
X213671Y43474D01*
X214860Y43298D01*
X231771Y55839D01*
X232982Y57390D01*
X234024Y59907D01*
X236603Y72871D01*
X246940Y83208D01*
Y84341D01*
X247859Y85260D01*
X248992D01*
X250070Y86338D01*
Y87470D01*
X250989Y88389D01*
X252121D01*
X253040Y89308D01*
Y90441D01*
X253959Y91360D01*
X255092D01*
X256303Y92571D01*
Y94650D01*
X255503Y95450D01*
Y96750D01*
X256303Y97550D01*
Y98850D01*
X255503Y99650D01*
Y100950D01*
X256303Y101750D01*
Y105009D01*
X255213Y106099D01*
G01X249988Y105792D02*
X248898Y104702D01*
Y98854D01*
X244314Y87785D01*
X232624Y76095D01*
X227000Y62518D01*
X199767Y35285D01*
X188441Y33033D01*
X55750D01*
X45057Y37462D01*
X42500Y40019D01*
X40780Y44172D01*
Y91607D01*
X38013Y98286D01*
Y98287D01*
X10724Y125576D01*
X10523Y126061D01*
Y309623D01*
X19400Y318500D01*
Y334727D01*
X17722Y338778D01*
X12614Y343886D01*
X9900Y350437D01*
Y422556D01*
X11535Y426503D01*
X15600Y430568D01*
X40898Y441045D01*
X74385D01*
X75870Y440430D01*
X86726D01*
X88585Y441200D01*
X95832D01*
X96960Y442328D01*
Y444393D01*
X95870Y445483D01*
G01X246488Y105792D02*
X247578Y104702D01*
Y99117D01*
X245758Y94722D01*
X244751Y94305D01*
X244235Y93057D01*
X244651Y92051D01*
X243195Y88533D01*
X240141Y85479D01*
X238938D01*
X237983Y84524D01*
Y83321D01*
X231505Y76843D01*
X225881Y63266D01*
X224912Y62297D01*
X223709D01*
X222754Y61342D01*
Y60139D01*
X221800Y59185D01*
X220597D01*
X219642Y58230D01*
Y57027D01*
X218688Y56073D01*
X217485D01*
X216530Y55118D01*
Y53915D01*
X199117Y36502D01*
X188311Y34353D01*
X56013D01*
X45805Y38581D01*
X43619Y40767D01*
X42100Y44435D01*
Y91870D01*
X39132Y99035D01*
X31069Y107098D01*
Y108301D01*
X30115Y109255D01*
X28912D01*
X11843Y126324D01*
Y309076D01*
X20720Y317953D01*
Y334990D01*
X18841Y339526D01*
X13733Y344634D01*
X11220Y350700D01*
Y365350D01*
X12020Y366150D01*
Y367450D01*
X11220Y368250D01*
Y370013D01*
X12070Y370863D01*
Y372213D01*
X11220Y373063D01*
Y422293D01*
X12654Y425755D01*
X16348Y429449D01*
X41161Y439725D01*
X74122D01*
X75607Y439110D01*
X86989D01*
X88848Y439880D01*
X96379D01*
X98280Y441781D01*
Y444393D01*
X99370Y445483D01*
G01X60622Y431273D02*
X61712Y430183D01*
Y421388D01*
X67070Y416030D01*
X82508D01*
X93058Y426580D01*
X100947D01*
X103147Y428780D01*
X107453D01*
X108538Y427695D01*
X115405D01*
X117270Y425830D01*
X139699D01*
X146206Y419323D01*
X148916Y418200D01*
X153700D01*
X156600Y415300D01*
Y408232D01*
X160140Y404692D01*
Y388424D01*
X159050Y387334D01*
G01X64122Y431273D02*
X63032Y430183D01*
Y421935D01*
X67617Y417350D01*
X81961D01*
X92511Y427900D01*
X100400D01*
X102600Y430100D01*
X108000D01*
X109085Y429015D01*
X115952D01*
X117817Y427150D01*
X140246D01*
X146954Y420442D01*
X149179Y419520D01*
X154247D01*
X157920Y415847D01*
Y408779D01*
X161460Y405239D01*
Y388424D01*
X162550Y387334D01*
G01X250749Y235301D02*
X251664Y236216D01*
Y237564D01*
X253120Y239020D01*
X255152D01*
X256032Y239900D01*
X258703D01*
X264400Y245597D01*
Y247999D01*
X276701Y260300D01*
X283934D01*
X288080Y264446D01*
Y270953D01*
X284716Y274317D01*
X282616D01*
X279280Y277653D01*
Y280674D01*
X276800Y286662D01*
Y309624D01*
X278880Y314647D01*
Y330320D01*
X274120Y335080D01*
X271253D01*
X268080Y338253D01*
Y344320D01*
X264863Y347537D01*
X257900Y364349D01*
Y389600D01*
X254500Y393000D01*
Y413751D01*
X249480Y425872D01*
Y427813D01*
X248909Y429191D01*
X241400Y436700D01*
X233700D01*
X230620Y439780D01*
X226353D01*
X223539Y442594D01*
X222449D01*
X221494Y443549D01*
Y444639D01*
X218733Y447400D01*
X211463D01*
X209000Y444937D01*
Y442433D01*
X207104Y440537D01*
X198650Y437035D01*
X189061D01*
X184691Y435225D01*
X179745D01*
X178975Y434455D01*
X177625D01*
X176855Y435225D01*
X171445D01*
X170675Y434455D01*
X169325D01*
X168555Y435225D01*
X163826D01*
X160601Y432000D01*
X154799D01*
X151219Y435580D01*
X145695D01*
X144865Y434750D01*
X143535D01*
X142705Y435580D01*
X141375D01*
X140545Y434750D01*
X139215D01*
X138385Y435580D01*
X120273D01*
X116120Y437300D01*
X100568D01*
X97648Y434380D01*
X77895D01*
X77065Y433550D01*
X75735D01*
X74905Y434380D01*
X71004D01*
X68589Y435380D01*
X57646D01*
X55160Y432894D01*
Y431564D01*
X55990Y430734D01*
Y429404D01*
X55160Y428574D01*
Y425290D01*
X56250Y424200D01*
G01X253898Y235301D02*
X253530Y235669D01*
X253434D01*
X252984Y236119D01*
Y237017D01*
X253667Y237700D01*
X255699D01*
X256579Y238580D01*
X259250D01*
X265720Y245050D01*
Y247452D01*
X277248Y258980D01*
X284481D01*
X289400Y263899D01*
Y271500D01*
X285263Y275637D01*
X283163D01*
X280600Y278200D01*
Y280937D01*
X278120Y286925D01*
Y309361D01*
X280200Y314384D01*
Y330867D01*
X274667Y336400D01*
X271800D01*
X269400Y338800D01*
Y344867D01*
X265982Y348285D01*
X259220Y364612D01*
Y390147D01*
X255820Y393547D01*
Y414014D01*
X250800Y426135D01*
Y428076D01*
X250028Y429939D01*
X241947Y438020D01*
X234247D01*
X231167Y441100D01*
X226900D01*
X219280Y448720D01*
X210916D01*
X207680Y445484D01*
Y442980D01*
X206356Y441656D01*
X198387Y438355D01*
X188798D01*
X184428Y436545D01*
X163279D01*
X160054Y433320D01*
X155346D01*
X151766Y436900D01*
X120536D01*
X116383Y438620D01*
X100021D01*
X97101Y435700D01*
X71267D01*
X68852Y436700D01*
X57099D01*
X53840Y433441D01*
Y425290D01*
X52750Y424200D01*
G01X260818Y234409D02*
X272542Y246133D01*
X276036Y247580D01*
X288647D01*
X291020Y249953D01*
Y252520D01*
X295557Y257057D01*
X299373Y266270D01*
Y268703D01*
X298281Y270887D01*
X296045Y276287D01*
Y285802D01*
X295700Y286635D01*
Y288094D01*
X295064Y289629D01*
X284010Y300683D01*
X283320Y302348D01*
Y303888D01*
X285200Y308427D01*
Y311509D01*
X283920Y314600D01*
Y333253D01*
X282901Y335714D01*
X273865Y349238D01*
X270163Y352940D01*
Y352941D01*
X263019Y370186D01*
X262916Y391875D01*
X259700Y399638D01*
Y414112D01*
X254700Y426183D01*
Y427922D01*
X253182Y431586D01*
X242447Y442321D01*
X237189Y444500D01*
X229567D01*
X228120Y445947D01*
Y450279D01*
X226379Y452020D01*
X226377D01*
X225552Y452845D01*
X220316D01*
X218324Y452020D01*
X209454D01*
X206684Y449250D01*
X197383D01*
X192609Y444476D01*
X182284Y440200D01*
X122553D01*
X118366Y441934D01*
X106134Y454166D01*
X100379Y456550D01*
X89251D01*
X87570Y454869D01*
X83347Y453120D01*
X81276D01*
X70363Y448600D01*
X61299D01*
X60220Y449679D01*
Y454290D01*
X58756Y455754D01*
X57572D01*
X56482Y456844D01*
G01X259932Y235383D02*
Y235390D01*
X261400Y236858D01*
Y237948D01*
X262355Y238903D01*
X263445D01*
X264399Y239857D01*
Y240947D01*
X265353Y241901D01*
X266443D01*
X267949Y243407D01*
Y244497D01*
X268903Y245451D01*
X269993D01*
X271794Y247252D01*
X275773Y248900D01*
X288100D01*
X289700Y250500D01*
Y253067D01*
X291439Y254806D01*
Y256040D01*
X292250Y256851D01*
X293484D01*
X294438Y257805D01*
X294978Y259110D01*
X294561Y260116D01*
X295078Y261364D01*
X296084Y261780D01*
X298053Y266533D01*
Y268391D01*
X297079Y270339D01*
X296434Y271898D01*
X295427Y272315D01*
X294910Y273563D01*
X295327Y274569D01*
X294725Y276024D01*
Y280655D01*
X293955Y281425D01*
Y282775D01*
X294725Y283545D01*
Y285539D01*
X294380Y286372D01*
Y287831D01*
X293945Y288881D01*
X292735Y290091D01*
X291645D01*
X290691Y291045D01*
Y292135D01*
X289385Y293441D01*
X288159D01*
X287341Y294259D01*
Y295485D01*
X282891Y299935D01*
X282000Y302085D01*
Y304151D01*
X283880Y308690D01*
Y311245D01*
X283879Y311246D01*
X282600Y314337D01*
Y332990D01*
X281731Y335089D01*
X272839Y348396D01*
X269044Y352192D01*
X261700Y369920D01*
X261597Y391609D01*
X258380Y399375D01*
Y413849D01*
X253380Y425920D01*
Y427659D01*
X252063Y430838D01*
X241699Y441202D01*
X236926Y443180D01*
X229020D01*
X226800Y445400D01*
Y449732D01*
X225832Y450700D01*
X225830D01*
X225005Y451525D01*
X220579D01*
X218587Y450700D01*
X210001D01*
X207231Y447930D01*
X197930D01*
X193357Y443357D01*
X182547Y438880D01*
X122290D01*
X117618Y440815D01*
X105386Y453047D01*
X100116Y455230D01*
X89798D01*
X88318Y453750D01*
X83610Y451800D01*
X81539D01*
X70626Y447280D01*
X60752D01*
X58900Y449132D01*
Y453743D01*
X58209Y454434D01*
X57572D01*
X56482Y453344D01*
G01X72150Y424199D02*
X73240Y423109D01*
Y421461D01*
X74801Y419900D01*
X79349D01*
X89929Y430480D01*
X99322D01*
X101622Y432780D01*
X108991D01*
X110206Y431565D01*
X117068D01*
X118933Y429700D01*
X149127D01*
X153232Y428000D01*
X157392D01*
X162527Y425873D01*
X166300Y422100D01*
Y397600D01*
X169996Y393904D01*
X178361Y390439D01*
X179940Y388860D01*
Y386724D01*
X178850Y385634D01*
G01X75650Y424199D02*
X74560Y423109D01*
Y422008D01*
X75348Y421220D01*
X78802D01*
X89382Y431800D01*
X98775D01*
X101075Y434100D01*
X109538D01*
X110753Y432885D01*
X117615D01*
X119480Y431020D01*
X149390D01*
X153495Y429320D01*
X157655D01*
X163275Y426992D01*
X167620Y422647D01*
Y398147D01*
X170744Y395023D01*
X179109Y391558D01*
X181260Y389407D01*
Y386724D01*
X182350Y385634D01*
G01X257338Y227772D02*
X259771D01*
X263800Y231801D01*
X264437Y233338D01*
X266191Y235092D01*
X268582Y236083D01*
X274296Y241795D01*
X275428Y243488D01*
X277335Y244280D01*
X295579D01*
X301827Y250528D01*
X306720Y262341D01*
Y287180D01*
X300809Y293091D01*
Y303859D01*
X298500Y306168D01*
Y320520D01*
X293800Y325220D01*
Y341967D01*
X285360Y350407D01*
X282884Y356384D01*
X269120Y370148D01*
Y406747D01*
X261420Y425337D01*
Y436380D01*
X250320Y447480D01*
Y455380D01*
X245600Y460100D01*
X239206D01*
X230804Y456620D01*
X217844D01*
X215828Y455785D01*
X208017D01*
X204752Y452520D01*
X195420D01*
X190212Y447312D01*
X182457Y444100D01*
X173000D01*
X167480Y446387D01*
X162976Y450891D01*
X161420Y454647D01*
X158847Y457220D01*
X151253D01*
X137553Y443520D01*
X126529D01*
X124909Y444191D01*
X112097Y457003D01*
Y458178D01*
X111178Y459097D01*
X110003D01*
X107680Y461420D01*
X89321D01*
X85621Y457720D01*
X80680D01*
X79850Y458550D01*
X78550D01*
X77720Y457720D01*
X71197D01*
X66450Y455754D01*
X64659D01*
X63569Y456844D01*
G01X257338Y229092D02*
X259224D01*
X262681Y232549D01*
X262680D01*
X263318Y234086D01*
X265443Y236211D01*
X267834Y237202D01*
X269344Y238711D01*
Y239801D01*
X270299Y240756D01*
X271389D01*
X273271Y242637D01*
X274552Y244555D01*
X277071Y245600D01*
X290155D01*
X290925Y246370D01*
X292275D01*
X293045Y245600D01*
X295032D01*
X300708Y251276D01*
X301216Y252504D01*
X300767Y253589D01*
X301276Y254818D01*
X302362Y255268D01*
X302361D01*
X303262Y257445D01*
X303263D01*
X302814Y258529D01*
X303323Y259759D01*
X304408Y260208D01*
X304407D01*
X305400Y262604D01*
Y265105D01*
X304570Y265935D01*
Y267265D01*
X305400Y268095D01*
Y270105D01*
X304570Y270935D01*
Y272265D01*
X305400Y273095D01*
Y276105D01*
X304570Y276935D01*
Y278265D01*
X305400Y279095D01*
Y286633D01*
X303374Y288659D01*
X302199D01*
X301259Y289599D01*
Y290774D01*
X299489Y292544D01*
Y303312D01*
X297180Y305621D01*
Y313405D01*
X296350Y314235D01*
Y315565D01*
X297180Y316395D01*
Y319973D01*
X292480Y324673D01*
Y341420D01*
X290479Y343421D01*
X289479D01*
X288421Y344479D01*
Y345479D01*
X284241Y349659D01*
X281765Y355636D01*
X267800Y369601D01*
Y406484D01*
X260100Y425074D01*
Y435833D01*
X249000Y446933D01*
Y454833D01*
X245053Y458780D01*
X239469D01*
X231067Y455300D01*
X218107D01*
X216091Y454465D01*
X208564D01*
X205299Y451200D01*
X195967D01*
X190960Y446193D01*
X182720Y442780D01*
X172737D01*
X166732Y445268D01*
X161857Y450143D01*
X160301Y453899D01*
X158300Y455900D01*
X151800D01*
X138100Y442200D01*
X126266D01*
X124161Y443072D01*
X107133Y460100D01*
X89868D01*
X86168Y456400D01*
X71460D01*
X66713Y454434D01*
X64659D01*
X63569Y453344D01*
G01X241338Y225890D02*
X240248Y226980D01*
X239321D01*
X237605Y228696D01*
X235380Y234069D01*
Y239047D01*
X237512Y241179D01*
X241072Y249771D01*
X245701Y254400D01*
X250100D01*
X252200Y252300D01*
X259333D01*
X271600Y264567D01*
Y271704D01*
X269400Y277016D01*
Y316404D01*
X265443Y325958D01*
X263958Y327443D01*
X263957D01*
X260843Y328733D01*
X259758Y328284D01*
X258528Y328793D01*
X258079Y329878D01*
X255593Y330908D01*
X252581Y333920D01*
X251225Y337194D01*
Y376905D01*
X250395Y377735D01*
Y379065D01*
X251225Y379895D01*
Y381505D01*
X250395Y382335D01*
Y383665D01*
X251225Y384495D01*
Y386775D01*
X248601Y389399D01*
X247426D01*
X246486Y390339D01*
Y391514D01*
X245546Y392454D01*
X244462Y395070D01*
X241832Y397700D01*
X233974D01*
X232895Y398779D01*
X231720D01*
X230779Y399720D01*
Y400895D01*
X228538Y403136D01*
X227745Y405049D01*
X227746D01*
X226660Y405498D01*
X226151Y406728D01*
X226601Y407812D01*
X226091Y409043D01*
X222754Y412380D01*
X220585D01*
X220135Y411930D01*
Y411240D01*
X221225Y410150D01*
G01X217725D02*
X218815Y411240D01*
Y412477D01*
X220038Y413700D01*
X223301D01*
X227210Y409791D01*
X229657Y403884D01*
X234521Y399020D01*
X242379D01*
X245581Y395818D01*
X246665Y393202D01*
X252545Y387322D01*
Y337457D01*
X253700Y334668D01*
X256341Y332027D01*
X264706Y328562D01*
X266562Y326706D01*
X270720Y316667D01*
Y277279D01*
X272920Y271967D01*
Y268495D01*
X273750Y267665D01*
Y266335D01*
X272920Y265505D01*
Y264020D01*
X259880Y250980D01*
X257195D01*
X256365Y250150D01*
X255035D01*
X254205Y250980D01*
X251653D01*
X249553Y253080D01*
X246248D01*
X245190Y252022D01*
Y250932D01*
X244235Y249977D01*
X243145D01*
X242191Y249023D01*
X238631Y240431D01*
X236700Y238500D01*
Y234332D01*
X238724Y229444D01*
X239868Y228300D01*
X240598D01*
X241300Y229002D01*
G01X239870Y237596D02*
X240700Y238426D01*
Y239500D01*
X241715Y240515D01*
X242931Y241020D01*
X247206D01*
X254400Y244000D01*
X258178D01*
X261000Y246822D01*
Y249268D01*
X276080Y264348D01*
Y272782D01*
X272700Y280945D01*
Y319211D01*
X271800Y321384D01*
Y324900D01*
X267931Y328769D01*
X264400Y337293D01*
Y343233D01*
X261787Y345846D01*
X254600Y363197D01*
Y388101D01*
X250100Y392601D01*
X248332Y396868D01*
X243200Y402000D01*
X234300D01*
X231311Y404989D01*
X228836Y410964D01*
X221375Y418425D01*
Y435025D01*
X217900Y438500D01*
X215761D01*
X214315Y439946D01*
Y441130D01*
X213225Y442220D01*
G01X242870Y237596D02*
X242020Y238446D01*
Y238953D01*
X242463Y239396D01*
X243195Y239700D01*
X247469D01*
X254663Y242680D01*
X258725D01*
X262320Y246275D01*
Y248721D01*
X277400Y263801D01*
Y273045D01*
X274020Y281208D01*
Y319474D01*
X273120Y321647D01*
Y325447D01*
X269050Y329517D01*
X265720Y337556D01*
Y343780D01*
X262906Y346594D01*
X255920Y363460D01*
Y388648D01*
X251219Y393349D01*
X249451Y397616D01*
X243747Y403320D01*
X234847D01*
X232430Y405737D01*
X229955Y411712D01*
X222695Y418972D01*
Y435572D01*
X218447Y439820D01*
X216308D01*
X215635Y440493D01*
Y441130D01*
X216725Y442220D01*
G01X375876Y-159873D02*
X376916Y-158833D01*
Y-145538D01*
X377988Y-144258D01*
X387686Y-142551D01*
X388415Y-141511D01*
X387604Y-136924D01*
X386556Y-136189D01*
X370674Y-138988D01*
X368736Y-137632D01*
X367736Y-131964D01*
X369092Y-130026D01*
X387037Y-126860D01*
X387767Y-125817D01*
X386956Y-121227D01*
X385914Y-120498D01*
X370588Y-123202D01*
X368655Y-121843D01*
X367652Y-116173D01*
X369008Y-114233D01*
X386531Y-111146D01*
X387261Y-110104D01*
X386451Y-105514D01*
X385408Y-104783D01*
X370665Y-107383D01*
X368725Y-106027D01*
X368629Y-105488D01*
X368630D01*
X367725Y-100358D01*
X369081Y-98420D01*
X386460Y-95352D01*
X387190Y-94311D01*
X386380Y-89722D01*
X385338Y-88993D01*
X370654Y-91582D01*
X368717Y-90225D01*
X368621Y-89686D01*
X368622D01*
X367716Y-84556D01*
X369073Y-82619D01*
X385383Y-79743D01*
X386113Y-78700D01*
X385303Y-74110D01*
X384261Y-73379D01*
X370651Y-75778D01*
X368713Y-74422D01*
X367713Y-68753D01*
X369069Y-66815D01*
X386257Y-63783D01*
X386987Y-62740D01*
X386176Y-58150D01*
X385136Y-57421D01*
X370547Y-59994D01*
X368610Y-58637D01*
X368514Y-58098D01*
X368515D01*
X367610Y-52968D01*
X368966Y-51030D01*
X387539Y-47752D01*
X388269Y-46710D01*
X387458Y-42121D01*
X386417Y-41391D01*
X370413Y-44214D01*
X368476Y-42857D01*
X367475Y-37187D01*
X368832Y-35250D01*
X387845Y-31896D01*
X388575Y-30854D01*
X387764Y-26264D01*
X386724Y-25535D01*
X370059Y-28472D01*
X368122Y-27116D01*
X368026Y-26577D01*
X368027D01*
X367122Y-21446D01*
X368470Y-19518D01*
X387874Y-15752D01*
X388298Y-15146D01*
X387489Y-10557D01*
X386393Y-9791D01*
X369740Y-12724D01*
X367802Y-11368D01*
X366801Y-5697D01*
X368158Y-3761D01*
X376532Y-2284D01*
X377262Y-1242D01*
X377004Y216D01*
Y11273D01*
X375964Y12313D01*
G01X379276Y-159873D02*
X378236Y-158833D01*
Y-146018D01*
X378691Y-145475D01*
X388453Y-143757D01*
X389811Y-141821D01*
X388809Y-136156D01*
X386866Y-134794D01*
X370983Y-137593D01*
X369941Y-136864D01*
X369131Y-132273D01*
X369860Y-131231D01*
X387805Y-128065D01*
X389163Y-126126D01*
X388161Y-120459D01*
X386223Y-119103D01*
X370899Y-121806D01*
X369861Y-121076D01*
X369048Y-116482D01*
X369777Y-115439D01*
X387299Y-112352D01*
X388657Y-110414D01*
X387657Y-104746D01*
X385718Y-103387D01*
X370974Y-105988D01*
X369930Y-105259D01*
X369120Y-100667D01*
X369849Y-99625D01*
X387228Y-96558D01*
X388586Y-94621D01*
X387585Y-88954D01*
X385647Y-87598D01*
X370964Y-90186D01*
X369922Y-89457D01*
X369112Y-84866D01*
X369841Y-83825D01*
X386151Y-80948D01*
X387508Y-79009D01*
X386509Y-73342D01*
X384571Y-71984D01*
X370960Y-74383D01*
X369918Y-73654D01*
X369108Y-69062D01*
X369837Y-68020D01*
X387025Y-64988D01*
X388383Y-63049D01*
X387382Y-57382D01*
X385446Y-56025D01*
X370859Y-58598D01*
X369815Y-57869D01*
X369005Y-53277D01*
X369734Y-52235D01*
X388307Y-48957D01*
X389665Y-47019D01*
X388664Y-41353D01*
X386727Y-39995D01*
X370723Y-42818D01*
X369681Y-42089D01*
X368871Y-37497D01*
X369600Y-36455D01*
X388613Y-33101D01*
X389971Y-31163D01*
X388970Y-25496D01*
X387034Y-24140D01*
X370368Y-27077D01*
X369327Y-26348D01*
X368517Y-21755D01*
X369246Y-20713D01*
X388650Y-16947D01*
X389693Y-15455D01*
X388695Y-9788D01*
X386702Y-8396D01*
X370049Y-11329D01*
X369007Y-10600D01*
X368197Y-6007D01*
X368926Y-4967D01*
X377300Y-3489D01*
X378658Y-1551D01*
X378324Y332D01*
Y11273D01*
X379364Y12313D01*
G01X375904Y68399D02*
X376944Y69439D01*
Y82194D01*
X378836Y84086D01*
X387473Y85610D01*
X388203Y86652D01*
X387392Y91242D01*
X386351Y91972D01*
X369590Y89017D01*
X367652Y90373D01*
X367556Y90912D01*
X367557D01*
X366651Y96043D01*
X368008Y97980D01*
X387591Y101434D01*
X388321Y102476D01*
X387511Y107066D01*
X386468Y107796D01*
X369625Y104827D01*
X367687Y106183D01*
X367591Y106722D01*
X367592D01*
X366686Y111853D01*
X368043Y113790D01*
X387524Y117226D01*
X388254Y118268D01*
X387443Y122858D01*
X386402Y123588D01*
X369741Y120651D01*
X367803Y122007D01*
X367707Y122546D01*
X367708D01*
X366802Y127677D01*
X368159Y129614D01*
X387536Y133032D01*
X388266Y134074D01*
X387455Y138664D01*
X386414Y139394D01*
X369782Y136462D01*
X367844Y137818D01*
X366843Y143489D01*
X368200Y145426D01*
X387564Y148841D01*
X388294Y149883D01*
X387484Y154473D01*
X386442Y155203D01*
X369702Y152251D01*
X367765Y153608D01*
X366764Y159279D01*
X368121Y161216D01*
X387612Y164653D01*
X388342Y165695D01*
X387532Y170285D01*
X386490Y171015D01*
X369591Y168035D01*
X367654Y169392D01*
X366653Y175063D01*
X368010Y177000D01*
X387582Y180451D01*
X388312Y181493D01*
X387502Y186083D01*
X386460Y186813D01*
X369660Y183851D01*
X367723Y185208D01*
X367627Y185747D01*
X367628D01*
X366722Y190878D01*
X368079Y192815D01*
X385519Y195891D01*
X386249Y196933D01*
X385438Y201523D01*
X384397Y202253D01*
X369539Y199634D01*
X367601Y200990D01*
X366600Y206660D01*
X367957Y208597D01*
X385559Y211702D01*
X386289Y212744D01*
X385478Y217334D01*
X384437Y218064D01*
X369481Y215427D01*
X367543Y216783D01*
X366542Y222453D01*
X367899Y224390D01*
X385472Y227490D01*
X386202Y228532D01*
X385391Y233122D01*
X384350Y233852D01*
X369513Y231236D01*
X367575Y232592D01*
X366575Y238263D01*
X367931Y240201D01*
X385614Y243319D01*
X386344Y244361D01*
X385533Y248951D01*
X384492Y249681D01*
X369507Y247039D01*
X367569Y248395D01*
X366569Y254065D01*
X367925Y256003D01*
X385490Y259101D01*
X386220Y260142D01*
X385410Y264732D01*
X384367Y265462D01*
X369576Y262855D01*
X367638Y264211D01*
X367542Y264750D01*
X367543D01*
X366637Y269881D01*
X367994Y271818D01*
X385288Y274869D01*
X386018Y275911D01*
X385208Y280501D01*
X384167Y281231D01*
X369733Y278685D01*
X367797Y280042D01*
X366797Y285713D01*
X368153Y287651D01*
X388176Y291180D01*
X388906Y292223D01*
X388095Y296814D01*
X387055Y297544D01*
X369642Y294473D01*
X367705Y295830D01*
X366704Y301500D01*
X368061Y303437D01*
X388352Y307016D01*
X389082Y308058D01*
X388271Y312648D01*
X387230Y313378D01*
X369547Y310261D01*
X367609Y311617D01*
X366608Y317287D01*
X367965Y319224D01*
X388370Y322823D01*
X389100Y323865D01*
X388289Y328455D01*
X387248Y329185D01*
X369685Y326088D01*
X367743Y327444D01*
X367647Y327983D01*
X367648D01*
X366742Y333114D01*
X368099Y335051D01*
X388390Y338630D01*
X389120Y339672D01*
X388309Y344262D01*
X387268Y344992D01*
X369601Y341877D01*
X367664Y343234D01*
X367568Y343773D01*
X367569D01*
X366663Y348904D01*
X368020Y350841D01*
X388564Y354464D01*
X389294Y355506D01*
X388483Y360096D01*
X387442Y360826D01*
X369486Y357660D01*
X367549Y359017D01*
X366548Y364688D01*
X367905Y366625D01*
X376570Y368153D01*
X377300Y369195D01*
X377004Y370869D01*
Y380545D01*
X375964Y381585D01*
G01X379304Y68399D02*
X378264Y69439D01*
Y81647D01*
X379475Y82858D01*
X388241Y84404D01*
X389599Y86342D01*
X388598Y92010D01*
X386661Y93368D01*
X369899Y90412D01*
X368857Y91141D01*
X368047Y95734D01*
X368776Y96775D01*
X388359Y100228D01*
X389717Y102166D01*
X388716Y107834D01*
X386778Y109192D01*
X369934Y106222D01*
X368892Y106951D01*
X368082Y111544D01*
X368811Y112585D01*
X388292Y116020D01*
X389650Y117958D01*
X388649Y123626D01*
X386712Y124984D01*
X370050Y122046D01*
X369008Y122775D01*
X368198Y127368D01*
X368927Y128409D01*
X388304Y131826D01*
X389662Y133764D01*
X388661Y139432D01*
X386724Y140790D01*
X370091Y137857D01*
X369049Y138586D01*
X368239Y143179D01*
X368968Y144221D01*
X388332Y147635D01*
X389690Y149573D01*
X388689Y155241D01*
X386752Y156599D01*
X370012Y153647D01*
X368970Y154376D01*
X368160Y158969D01*
X368889Y160010D01*
X388380Y163447D01*
X389738Y165385D01*
X388737Y171053D01*
X386800Y172411D01*
X369901Y169431D01*
X368859Y170160D01*
X368049Y174753D01*
X368778Y175794D01*
X388350Y179245D01*
X389708Y181183D01*
X388707Y186851D01*
X386770Y188209D01*
X369970Y185247D01*
X368928Y185976D01*
X368118Y190569D01*
X368847Y191610D01*
X386287Y194685D01*
X387645Y196623D01*
X386644Y202291D01*
X384707Y203649D01*
X369848Y201029D01*
X368806Y201758D01*
X367996Y206351D01*
X368725Y207392D01*
X386327Y210496D01*
X387685Y212434D01*
X386684Y218102D01*
X384747Y219460D01*
X369790Y216822D01*
X368748Y217551D01*
X367938Y222144D01*
X368667Y223185D01*
X386240Y226284D01*
X387598Y228222D01*
X386597Y233890D01*
X384660Y235248D01*
X369822Y232631D01*
X368780Y233360D01*
X367970Y237954D01*
X368699Y238996D01*
X386382Y242113D01*
X387740Y244051D01*
X386739Y249719D01*
X384802Y251077D01*
X369816Y248434D01*
X368774Y249163D01*
X367964Y253756D01*
X368693Y254798D01*
X386258Y257895D01*
X387616Y259832D01*
X386615Y265500D01*
X384676Y266857D01*
X369885Y264250D01*
X368843Y264979D01*
X368033Y269572D01*
X368762Y270613D01*
X386056Y273663D01*
X387414Y275601D01*
X386414Y281269D01*
X384477Y282627D01*
X370043Y280081D01*
X369003Y280810D01*
X368192Y285404D01*
X368921Y286446D01*
X388944Y289975D01*
X390302Y291914D01*
X389301Y297582D01*
X387365Y298940D01*
X369952Y295869D01*
X368910Y296598D01*
X368100Y301191D01*
X368829Y302232D01*
X389120Y305810D01*
X390478Y307748D01*
X389477Y313416D01*
X387540Y314774D01*
X369856Y311656D01*
X368814Y312385D01*
X368004Y316978D01*
X368733Y318019D01*
X389138Y321617D01*
X390496Y323555D01*
X389495Y329223D01*
X387558Y330581D01*
X369993Y327483D01*
X368948Y328212D01*
X368138Y332805D01*
X368867Y333846D01*
X389158Y337424D01*
X390516Y339362D01*
X389515Y345030D01*
X387578Y346388D01*
X369911Y343273D01*
X368869Y344002D01*
X368059Y348595D01*
X368788Y349636D01*
X389332Y353258D01*
X390690Y355196D01*
X389689Y360864D01*
X387752Y362222D01*
X369796Y359056D01*
X368754Y359785D01*
X367944Y364378D01*
X368673Y365419D01*
X377338Y366947D01*
X378696Y368886D01*
X378324Y370985D01*
Y380545D01*
X379364Y381585D01*
G01X451000Y126000D02*
X447110D01*
X446660Y126450D01*
Y134373D01*
X444987Y136046D01*
X417670D01*
X416770Y136946D01*
Y140096D01*
X417670Y140996D01*
X473617D01*
X475290Y142669D01*
Y146913D01*
X473617Y148586D01*
X417320D01*
X416420Y149486D01*
Y152636D01*
X417320Y153536D01*
X473617D01*
X475290Y155209D01*
Y159453D01*
X473617Y161126D01*
X417040D01*
X416140Y162026D01*
Y165176D01*
X417040Y166076D01*
X473617D01*
X475290Y167749D01*
Y171993D01*
X473617Y173666D01*
X416870D01*
X415970Y174566D01*
Y177716D01*
X416870Y178616D01*
X473617D01*
X475290Y180289D01*
Y184533D01*
X473617Y186206D01*
X416930D01*
X416030Y187106D01*
Y190256D01*
X416930Y191156D01*
X444987D01*
X446660Y192829D01*
Y199550D01*
X447110Y200000D01*
X451000D01*
G01X441000Y126000D02*
X444890D01*
X445340Y126450D01*
Y133826D01*
X444440Y134726D01*
X417123D01*
X415450Y136399D01*
Y140643D01*
X417123Y142316D01*
X473070D01*
X473970Y143216D01*
Y146366D01*
X473070Y147266D01*
X416773D01*
X415100Y148939D01*
Y153183D01*
X416773Y154856D01*
X473070D01*
X473970Y155756D01*
Y158906D01*
X473070Y159806D01*
X416493D01*
X414820Y161479D01*
Y165723D01*
X416493Y167396D01*
X473070D01*
X473970Y168296D01*
Y171446D01*
X473070Y172346D01*
X416323D01*
X414650Y174019D01*
Y178263D01*
X416323Y179936D01*
X473070D01*
X473970Y180836D01*
Y183986D01*
X473070Y184886D01*
X416383D01*
X414710Y186559D01*
Y190803D01*
X416383Y192476D01*
X444440D01*
X445340Y193376D01*
Y199550D01*
X444890Y200000D01*
X441000D01*
M02*
